FILE_TYPE = MACRO_DRAWING;
SET COLOR_WIRE YELLOW;
SET COLOR_PROP ORANGE;
SET COLOR_DOT WHITE;
SET COLOR_ARC YELLOW;
SET COLOR_BODY GREEN;
SET COLOR_NOTE PURPLE;
SET PROP_DISPLAY VALUE;
SET PAGE_NUMBER P264;
FORCEADD OFFPAGE..1
(-11825 3850);
FORCEPROP 2 LAST $XR1 279 
J 0
(-12227 3850);
DISPLAY 0.638298 (-12227 3850);
PAINT MONO (-12227 3850);
FORCEPROP 2 LAST $XR0 278 
J 0
(-12107 3850);
DISPLAY 0.638298 (-12107 3850);
PAINT MONO (-12107 3850);
FORCEPROP 1 LAST COMMENT_BODY TRUE
J 0
(-11700 3750);
DISPLAY 0.872340 (-11700 3750);
PAINT GREEN (-11700 3750);
DISPLAY INVISIBLE (-11700 3750);
FORCEPROP 1 LAST OFFPAGE TRUE
J 0
(-11500 3725);
DISPLAY 0.872340 (-11500 3725);
PAINT GREEN (-11500 3725);
DISPLAY INVISIBLE (-11500 3725);
FORCEPROP 2 LAST CDS_LIB standard
J 0
(-11825 3850);
DISPLAY INVISIBLE (-11825 3850);
FORCEPROP 2 LAST PATH I1
J 0
(-12100 3900);
DISPLAY 1.021277 (-12100 3900);
DISPLAY INVISIBLE (-12100 3900);
FORCEADD Q_RES..1
(-9775 3500);
FORCEPROP 1 LAST PART_NUMBER CS04992FB07
J 0
(-9875 3425);
DISPLAY 0.617021 (-9875 3425);
PAINT BLUE (-9875 3425);
DISPLAY INVISIBLE (-9875 3425);
FORCEPROP 1 LAST TOLERANCE 1%
J 0
(-9675 3550);
DISPLAY 0.617021 (-9675 3550);
PAINT SKYBLUE (-9675 3550);
FORCEPROP 1 LAST VALUE 49.9
J 2
(-9400 3500);
DISPLAY 0.617021 (-9400 3500);
PAINT SKYBLUE (-9400 3500);
FORCEPROP 1 LAST MATERIAL CHIP
J 0
(-9625 3550);
DISPLAY 0.617021 (-9625 3550);
PAINT SKYBLUE (-9625 3550);
FORCEPROP 1 LAST WATTAGE 1/16W
J 2
(-9575 3375);
DISPLAY 0.617021 (-9575 3375);
PAINT SKYBLUE (-9575 3375);
FORCEPROP 1 LAST PACK_TYPE 0402LF
J 0
(-9875 3375);
DISPLAY 0.617021 (-9875 3375);
PAINT SKYBLUE (-9875 3375);
FORCEPROP 1 LAST LOCATION PR1390
J 0
(-10000 3500);
DISPLAY 0.617021 (-10000 3500);
PAINT AQUA (-10000 3500);
FORCEPROP 1 LASTPIN (-9875 3500) $PN 1
J 0
(-9863 3512);
DISPLAY 0.617021 (-9863 3512);
FORCEPROP 1 LASTPIN (-9675 3500) $PN 2
J 0
(-9713 3512);
DISPLAY 0.617021 (-9713 3512);
FORCEPROP 2 LAST CDS_LIB pure_quanta
J 0
(-9775 3500);
PAINT MONO (-9775 3500);
DISPLAY INVISIBLE (-9775 3500);
FORCEPROP 1 LAST PATH I10
J 0
(-9825 3650);
DISPLAY 0.978723 (-9825 3650);
PAINT WHITE (-9825 3650);
DISPLAY INVISIBLE (-9825 3650);
FORCEPROP 2 LAST $SEC 1
J 0
(-9825 3700);
DISPLAY 0.680851 (-9825 3700);
PAINT MONO (-9825 3700);
DISPLAY INVISIBLE (-9825 3700);
FORCEPROP 2 LAST CDS_SEC 1
J 0
(-9825 3700);
DISPLAY 1.021277 (-9825 3700);
DISPLAY INVISIBLE (-9825 3700);
FORCEADD Q_RES..1
(-9775 3600);
FORCEPROP 1 LAST PART_NUMBER CS04992FB07
J 0
(-9875 3525);
DISPLAY 0.510638 (-9875 3525);
PAINT BLUE (-9875 3525);
DISPLAY INVISIBLE (-9875 3525);
FORCEPROP 1 LAST TOLERANCE 1%
J 0
(-9675 3650);
DISPLAY 0.617021 (-9675 3650);
PAINT SKYBLUE (-9675 3650);
FORCEPROP 1 LAST MATERIAL CHIP
J 0
(-9625 3650);
DISPLAY 0.617021 (-9625 3650);
PAINT SKYBLUE (-9625 3650);
FORCEPROP 1 LAST VALUE 49.9
J 2
(-9400 3600);
DISPLAY 0.617021 (-9400 3600);
PAINT SKYBLUE (-9400 3600);
FORCEPROP 1 LAST LOCATION PR1380
J 0
(-10000 3600);
DISPLAY 0.617021 (-10000 3600);
PAINT AQUA (-10000 3600);
FORCEPROP 1 LASTPIN (-9875 3600) $PN 1
J 0
(-9863 3612);
DISPLAY 0.617021 (-9863 3612);
FORCEPROP 1 LASTPIN (-9675 3600) $PN 2
J 0
(-9713 3612);
DISPLAY 0.617021 (-9713 3612);
FORCEPROP 1 LAST PACK_TYPE 0402LF
J 0
(-9875 3475);
DISPLAY 0.510638 (-9875 3475);
PAINT SKYBLUE (-9875 3475);
DISPLAY INVISIBLE (-9875 3475);
FORCEPROP 1 LAST WATTAGE 1/16W
J 2
(-9575 3475);
DISPLAY 0.510638 (-9575 3475);
PAINT SKYBLUE (-9575 3475);
DISPLAY INVISIBLE (-9575 3475);
FORCEPROP 2 LAST CDS_LIB pure_quanta
J 0
(-9775 3600);
PAINT MONO (-9775 3600);
DISPLAY INVISIBLE (-9775 3600);
FORCEPROP 1 LAST PATH I11
J 0
(-9825 3750);
DISPLAY 0.978723 (-9825 3750);
PAINT WHITE (-9825 3750);
DISPLAY INVISIBLE (-9825 3750);
FORCEPROP 2 LAST $SEC 1
J 0
(-9825 3800);
DISPLAY 0.680851 (-9825 3800);
PAINT MONO (-9825 3800);
DISPLAY INVISIBLE (-9825 3800);
FORCEPROP 2 LAST CDS_SEC 1
J 0
(-9825 3800);
DISPLAY 1.021277 (-9825 3800);
DISPLAY INVISIBLE (-9825 3800);
FORCEADD OFFPAGE..5
(-9750 4700);
FORCEPROP 1 LAST COMMENT_BODY TRUE
J 0
(-9650 4625);
DISPLAY 0.872340 (-9650 4625);
PAINT GREEN (-9650 4625);
DISPLAY INVISIBLE (-9650 4625);
FORCEPROP 1 LAST OFFPAGE TRUE
J 0
(-9425 4575);
DISPLAY 0.872340 (-9425 4575);
PAINT GREEN (-9425 4575);
DISPLAY INVISIBLE (-9425 4575);
FORCEPROP 2 LAST CDS_LIB standard
J 0
(-9750 4700);
DISPLAY INVISIBLE (-9750 4700);
FORCEPROP 2 LAST PATH I12
J 0
(-9700 4775);
DISPLAY 1.021277 (-9700 4775);
DISPLAY INVISIBLE (-9700 4775);
FORCEADD Q_RES..2
(-9600 5250);
FORCEPROP 1 LAST PART_NUMBER CS21002FB06
J 0
(-9575 5125);
DISPLAY 0.617021 (-9575 5125);
PAINT BLUE (-9575 5125);
DISPLAY INVISIBLE (-9575 5125);
FORCEPROP 1 LAST PACK_TYPE 0402LF
J 0
(-9575 5075);
DISPLAY 0.617021 (-9575 5075);
PAINT SKYBLUE (-9575 5075);
FORCEPROP 1 LAST VALUE 1K
J 0
(-9570 5325);
DISPLAY 0.617021 (-9570 5325);
PAINT SKYBLUE (-9570 5325);
FORCEPROP 1 LAST TOLERANCE 1%
J 0
(-9570 5275);
DISPLAY 0.617021 (-9570 5275);
PAINT SKYBLUE (-9570 5275);
FORCEPROP 1 LAST MATERIAL CHIP
J 0
(-9575 5175);
DISPLAY 0.617021 (-9575 5175);
PAINT SKYBLUE (-9575 5175);
FORCEPROP 1 LAST WATTAGE 1/16W
J 0
(-9575 5225);
DISPLAY 0.617021 (-9575 5225);
PAINT SKYBLUE (-9575 5225);
FORCEPROP 1 LAST LOCATION PR370
J 0
(-9575 5375);
DISPLAY 0.617021 (-9575 5375);
PAINT AQUA (-9575 5375);
FORCEPROP 1 LASTPIN (-9600 5350) $PN 1
J 0
(-9595 5312);
DISPLAY 0.617021 (-9595 5312);
PAINT MONO (-9595 5312);
FORCEPROP 1 LASTPIN (-9600 5150) $PN 2
J 0
(-9595 5160);
DISPLAY 0.617021 (-9595 5160);
PAINT MONO (-9595 5160);
FORCEPROP 2 LAST CDS_LIB pure_quanta
J 0
(-9600 5250);
DISPLAY INVISIBLE (-9600 5250);
FORCEPROP 1 LAST PATH I13
J 0
(-9550 5425);
DISPLAY 0.978723 (-9550 5425);
PAINT WHITE (-9550 5425);
DISPLAY INVISIBLE (-9550 5425);
FORCEPROP 1 LAST LOCATION PR370
J 0
(-9575 5425);
DISPLAY 1.021277 (-9575 5425);
PAINT AQUA (-9575 5425);
DISPLAY INVISIBLE (-9575 5425);
FORCEPROP 0 LAST $SEC 1
J 0
(-9575 5425);
DISPLAY 0.680851 (-9575 5425);
PAINT MONO (-9575 5425);
DISPLAY INVISIBLE (-9575 5425);
FORCEPROP 0 LAST CDS_SEC 1
J 0
(-9575 5425);
DISPLAY 1.021277 (-9575 5425);
DISPLAY INVISIBLE (-9575 5425);
FORCEADD Q_RES..2
(-9275 5250);
FORCEPROP 1 LAST PART_NUMBER CS21002FB06
J 0
(-9250 5125);
DISPLAY 0.617021 (-9250 5125);
PAINT BLUE (-9250 5125);
DISPLAY INVISIBLE (-9250 5125);
FORCEPROP 1 LAST TOLERANCE 1%
J 0
(-9245 5275);
DISPLAY 0.617021 (-9245 5275);
PAINT SKYBLUE (-9245 5275);
FORCEPROP 1 LAST WATTAGE 1/16W
J 0
(-9250 5225);
DISPLAY 0.617021 (-9250 5225);
PAINT SKYBLUE (-9250 5225);
FORCEPROP 1 LAST PACK_TYPE 0402LF
J 0
(-9250 5075);
DISPLAY 0.617021 (-9250 5075);
PAINT SKYBLUE (-9250 5075);
FORCEPROP 1 LAST VALUE 1K
J 0
(-9245 5325);
DISPLAY 0.617021 (-9245 5325);
PAINT SKYBLUE (-9245 5325);
FORCEPROP 1 LAST MATERIAL CHIP
J 0
(-9250 5175);
DISPLAY 0.617021 (-9250 5175);
PAINT SKYBLUE (-9250 5175);
FORCEPROP 1 LAST LOCATION PR372
J 0
(-9250 5375);
DISPLAY 0.617021 (-9250 5375);
PAINT AQUA (-9250 5375);
FORCEPROP 1 LASTPIN (-9275 5350) $PN 1
J 0
(-9270 5312);
DISPLAY 0.617021 (-9270 5312);
PAINT MONO (-9270 5312);
FORCEPROP 1 LASTPIN (-9275 5150) $PN 2
J 0
(-9270 5160);
DISPLAY 0.617021 (-9270 5160);
PAINT MONO (-9270 5160);
FORCEPROP 2 LAST CDS_LIB pure_quanta
J 0
(-9275 5250);
DISPLAY INVISIBLE (-9275 5250);
FORCEPROP 1 LAST PATH I14
J 0
(-9225 5425);
DISPLAY 0.978723 (-9225 5425);
PAINT WHITE (-9225 5425);
DISPLAY INVISIBLE (-9225 5425);
FORCEPROP 1 LAST LOCATION PR372
J 0
(-9250 5425);
DISPLAY 1.021277 (-9250 5425);
PAINT AQUA (-9250 5425);
DISPLAY INVISIBLE (-9250 5425);
FORCEPROP 0 LAST $SEC 1
J 0
(-9250 5425);
DISPLAY 0.680851 (-9250 5425);
PAINT MONO (-9250 5425);
DISPLAY INVISIBLE (-9250 5425);
FORCEPROP 0 LAST CDS_SEC 1
J 0
(-9250 5425);
DISPLAY 1.021277 (-9250 5425);
DISPLAY INVISIBLE (-9250 5425);
FORCEADD OFFPAGE..1
(-11725 6575);
FORCEPROP 2 LAST $XR0 16 
J 0
(-12036 6575);
DISPLAY 0.638298 (-12036 6575);
PAINT MONO (-12036 6575);
FORCEPROP 1 LAST COMMENT_BODY TRUE
J 0
(-11600 6475);
DISPLAY 0.872340 (-11600 6475);
PAINT GREEN (-11600 6475);
DISPLAY INVISIBLE (-11600 6475);
FORCEPROP 1 LAST OFFPAGE TRUE
J 0
(-11400 6450);
DISPLAY 0.872340 (-11400 6450);
PAINT GREEN (-11400 6450);
DISPLAY INVISIBLE (-11400 6450);
FORCEPROP 2 LAST CDS_LIB standard
J 0
(-11725 6575);
DISPLAY INVISIBLE (-11725 6575);
FORCEPROP 2 LAST PATH I15
J 0
(-12025 6625);
DISPLAY 1.021277 (-12025 6625);
DISPLAY INVISIBLE (-12025 6625);
FORCEADD OFFPAGE..1
(-11725 6950);
FORCEPROP 2 LAST $XR0 16 
J 0
(-12036 6950);
DISPLAY 0.638298 (-12036 6950);
PAINT MONO (-12036 6950);
FORCEPROP 1 LAST COMMENT_BODY TRUE
J 0
(-11600 6850);
DISPLAY 0.872340 (-11600 6850);
PAINT GREEN (-11600 6850);
DISPLAY INVISIBLE (-11600 6850);
FORCEPROP 1 LAST OFFPAGE TRUE
J 0
(-11400 6825);
DISPLAY 0.872340 (-11400 6825);
PAINT GREEN (-11400 6825);
DISPLAY INVISIBLE (-11400 6825);
FORCEPROP 2 LAST CDS_LIB standard
J 0
(-11725 6950);
DISPLAY INVISIBLE (-11725 6950);
FORCEPROP 2 LAST PATH I16
J 0
(-12025 7000);
DISPLAY 1.021277 (-12025 7000);
DISPLAY INVISIBLE (-12025 7000);
FORCEADD UNIVERSAL_GND..1
(-12100 8325);
FORCEPROP 3 LASTPIN (-12100 8375) SIG_NAME GND\g
J 0
(-12090 8385);
DISPLAY 0.659574 (-12090 8385);
PAINT MONO (-12090 8385);
DISPLAY INVISIBLE (-12090 8385);
FORCEPROP 1 LAST HDL_POWER GND
J 1
(-12075 8250);
DISPLAY 0.872340 (-12075 8250);
PAINT GREEN (-12075 8250);
DISPLAY INVISIBLE (-12075 8250);
FORCEPROP 2 LAST CDS_LIB logical_power
J 0
(-12100 8325);
PAINT MONO (-12100 8325);
DISPLAY INVISIBLE (-12100 8325);
FORCEPROP 1 LAST PATH I17
J 0
(-12025 8325);
DISPLAY 0.872340 (-12025 8325);
PAINT AQUA (-12025 8325);
DISPLAY INVISIBLE (-12025 8325);
FORCEADD Q_CAP..1
(-12100 8675);
FORCEPROP 1 LAST PART_NUMBER CH6101MEB03
J 0
(-12050 8525);
DISPLAY 0.617021 (-12050 8525);
PAINT BLUE (-12050 8525);
DISPLAY INVISIBLE (-12050 8525);
FORCEPROP 1 LAST TOLERANCE 20%
J 0
(-12050 8625);
DISPLAY 0.617021 (-12050 8625);
PAINT SKYBLUE (-12050 8625);
FORCEPROP 1 LAST MATERIAL X6S
J 0
(-12050 8575);
DISPLAY 0.617021 (-12050 8575);
PAINT SKYBLUE (-12050 8575);
FORCEPROP 1 LAST VOLTAGE 6.3V
J 0
(-12050 8675);
DISPLAY 0.617021 (-12050 8675);
PAINT SKYBLUE (-12050 8675);
FORCEPROP 1 LAST VALUE 10UF
J 0
(-12050 8725);
DISPLAY 0.617021 (-12050 8725);
PAINT SKYBLUE (-12050 8725);
FORCEPROP 1 LAST PACK_TYPE C0402
J 0
(-12050 8475);
DISPLAY 0.617021 (-12050 8475);
PAINT SKYBLUE (-12050 8475);
FORCEPROP 1 LAST LOCATION C2443
J 0
(-12050 8775);
DISPLAY 0.723404 (-12050 8775);
PAINT AQUA (-12050 8775);
FORCEPROP 1 LASTPIN (-12100 8775) $PN 1
J 0
(-12090 8755);
DISPLAY 0.617021 (-12090 8755);
FORCEPROP 1 LASTPIN (-12100 8575) $PN 2
J 0
(-12090 8555);
DISPLAY 0.617021 (-12090 8555);
FORCEPROP 2 LAST CDS_LIB pure_quanta
J 0
(-12100 8675);
PAINT MONO (-12100 8675);
DISPLAY INVISIBLE (-12100 8675);
FORCEPROP 1 LAST PATH I18
J 0
(-12050 8825);
DISPLAY 0.978723 (-12050 8825);
PAINT WHITE (-12050 8825);
DISPLAY INVISIBLE (-12050 8825);
FORCEPROP 2 LAST $SEC 1
J 0
(-12050 8875);
DISPLAY 0.680851 (-12050 8875);
PAINT MONO (-12050 8875);
DISPLAY INVISIBLE (-12050 8875);
FORCEPROP 2 LAST CDS_SEC 1
J 0
(-12050 8875);
DISPLAY 1.021277 (-12050 8875);
DISPLAY INVISIBLE (-12050 8875);
FORCEADD Q_CAP..1
(-11875 8675);
FORCEPROP 1 LAST PART_NUMBER CH4104K1B00
J 0
(-11825 8425);
DISPLAY 0.617021 (-11825 8425);
PAINT BLUE (-11825 8425);
DISPLAY INVISIBLE (-11825 8425);
FORCEPROP 1 LAST VALUE 0.1UF
J 0
(-11825 8725);
DISPLAY 0.617021 (-11825 8725);
PAINT SKYBLUE (-11825 8725);
FORCEPROP 1 LAST VOLTAGE 25V
J 0
(-11825 8675);
DISPLAY 0.617021 (-11825 8675);
PAINT SKYBLUE (-11825 8675);
FORCEPROP 1 LAST TOLERANCE 10%
J 0
(-11825 8625);
DISPLAY 0.617021 (-11825 8625);
PAINT SKYBLUE (-11825 8625);
FORCEPROP 1 LAST MATERIAL X7R
J 0
(-11825 8575);
DISPLAY 0.617021 (-11825 8575);
PAINT SKYBLUE (-11825 8575);
FORCEPROP 1 LAST PACK_TYPE 0402
J 0
(-11825 8475);
DISPLAY 0.617021 (-11825 8475);
PAINT SKYBLUE (-11825 8475);
FORCEPROP 1 LAST LOCATION C2444
J 0
(-11825 8775);
DISPLAY 0.723404 (-11825 8775);
PAINT AQUA (-11825 8775);
FORCEPROP 1 LASTPIN (-11875 8775) $PN 1
J 0
(-11865 8755);
DISPLAY 0.617021 (-11865 8755);
FORCEPROP 1 LASTPIN (-11875 8575) $PN 2
J 0
(-11865 8555);
DISPLAY 0.617021 (-11865 8555);
FORCEPROP 2 LAST CDS_LIB pure_quanta
J 0
(-11875 8675);
PAINT MONO (-11875 8675);
DISPLAY INVISIBLE (-11875 8675);
FORCEPROP 1 LAST PATH I19
J 0
(-11825 8825);
DISPLAY 0.978723 (-11825 8825);
PAINT WHITE (-11825 8825);
DISPLAY INVISIBLE (-11825 8825);
FORCEPROP 2 LAST $SEC 1
J 0
(-11825 8875);
DISPLAY 0.680851 (-11825 8875);
PAINT MONO (-11825 8875);
DISPLAY INVISIBLE (-11825 8875);
FORCEPROP 2 LAST CDS_SEC 1
J 0
(-11825 8875);
DISPLAY 1.021277 (-11825 8875);
DISPLAY INVISIBLE (-11825 8875);
FORCEADD OFFPAGE..1
(-11150 3500);
FORCEPROP 2 LAST $XR0 251 
J 0
(-11432 3500);
DISPLAY 0.638298 (-11432 3500);
PAINT MONO (-11432 3500);
FORCEPROP 1 LAST COMMENT_BODY TRUE
J 0
(-11025 3400);
DISPLAY 0.872340 (-11025 3400);
PAINT GREEN (-11025 3400);
DISPLAY INVISIBLE (-11025 3400);
FORCEPROP 1 LAST OFFPAGE TRUE
J 0
(-10825 3375);
DISPLAY 0.872340 (-10825 3375);
PAINT GREEN (-10825 3375);
DISPLAY INVISIBLE (-10825 3375);
FORCEPROP 2 LAST CDS_LIB standard
J 0
(-11150 3500);
PAINT MONO (-11150 3500);
DISPLAY INVISIBLE (-11150 3500);
FORCEPROP 2 LAST PATH I2
J 0
(-11425 3550);
DISPLAY 1.021277 (-11425 3550);
DISPLAY INVISIBLE (-11425 3550);
FORCEADD VCC15..1
(-12100 8950);
FORCEPROP 3 LASTPIN (-12100 8900) SIG_NAME PVNN_TERM_CPU0\g
J 0
(-12090 8910);
DISPLAY 0.659574 (-12090 8910);
PAINT MONO (-12090 8910);
DISPLAY INVISIBLE (-12090 8910);
FORCEPROP 1 LAST HDL_POWER PVNN_TERM_CPU0
J 1
(-12100 9000);
DISPLAY 0.617021 (-12100 9000);
PAINT GREEN (-12100 9000);
FORCEPROP 2 LAST CDS_LIB logical_power
J 0
(-12100 8950);
PAINT MONO (-12100 8950);
DISPLAY INVISIBLE (-12100 8950);
FORCEPROP 1 LAST PATH I20
J 0
(-12050 8975);
DISPLAY 0.872340 (-12050 8975);
PAINT AQUA (-12050 8975);
DISPLAY INVISIBLE (-12050 8975);
FORCEADD OFFPAGE..6
(-11200 7650);
FORCEPROP 2 LAST $XR1 274 
J 0
(-11600 7650);
DISPLAY 0.638298 (-11600 7650);
PAINT MONO (-11600 7650);
FORCEPROP 2 LAST $XR0 241 
J 0
(-11480 7650);
DISPLAY 0.638298 (-11480 7650);
PAINT MONO (-11480 7650);
FORCEPROP 1 LAST COMMENT_BODY TRUE
J 0
(-11100 7575);
DISPLAY 0.872340 (-11100 7575);
PAINT GREEN (-11100 7575);
DISPLAY INVISIBLE (-11100 7575);
FORCEPROP 1 LAST OFFPAGE TRUE
J 0
(-10875 7525);
DISPLAY 0.872340 (-10875 7525);
PAINT GREEN (-10875 7525);
DISPLAY INVISIBLE (-10875 7525);
FORCEPROP 2 LAST CDS_LIB standard
J 0
(-11200 7650);
DISPLAY INVISIBLE (-11200 7650);
FORCEPROP 2 LAST PATH I21
J 0
(-11475 7700);
DISPLAY 1.021277 (-11475 7700);
DISPLAY INVISIBLE (-11475 7700);
FORCEADD OFFPAGE..1
(-11200 7800);
FORCEPROP 2 LAST $XR1 274 
J 0
(-11572 7800);
DISPLAY 0.638298 (-11572 7800);
PAINT MONO (-11572 7800);
FORCEPROP 2 LAST $XR0 241 
J 0
(-11452 7800);
DISPLAY 0.638298 (-11452 7800);
PAINT MONO (-11452 7800);
FORCEPROP 1 LAST COMMENT_BODY TRUE
J 0
(-11075 7700);
DISPLAY 0.872340 (-11075 7700);
PAINT GREEN (-11075 7700);
DISPLAY INVISIBLE (-11075 7700);
FORCEPROP 1 LAST OFFPAGE TRUE
J 0
(-10875 7675);
DISPLAY 0.872340 (-10875 7675);
PAINT GREEN (-10875 7675);
DISPLAY INVISIBLE (-10875 7675);
FORCEPROP 2 LAST CDS_LIB standard
J 0
(-11200 7800);
DISPLAY INVISIBLE (-11200 7800);
FORCEPROP 2 LAST PATH I22
J 0
(-11450 7850);
DISPLAY 1.021277 (-11450 7850);
DISPLAY INVISIBLE (-11450 7850);
FORCEADD OFFPAGE..5
(-10950 8200);
FORCEPROP 2 LAST $XR0 14 
J 0
(-11204 8200);
DISPLAY 0.638298 (-11204 8200);
PAINT MONO (-11204 8200);
FORCEPROP 1 LAST COMMENT_BODY TRUE
J 0
(-10850 8125);
DISPLAY 0.872340 (-10850 8125);
PAINT GREEN (-10850 8125);
DISPLAY INVISIBLE (-10850 8125);
FORCEPROP 1 LAST OFFPAGE TRUE
J 0
(-10625 8075);
DISPLAY 0.872340 (-10625 8075);
PAINT GREEN (-10625 8075);
DISPLAY INVISIBLE (-10625 8075);
FORCEPROP 2 LAST CDS_LIB standard
J 0
(-10950 8200);
DISPLAY INVISIBLE (-10950 8200);
FORCEPROP 2 LAST PATH I23
J 0
(-11200 8250);
DISPLAY 1.021277 (-11200 8250);
DISPLAY INVISIBLE (-11200 8250);
FORCEADD Q_RES..1
(-11350 8575);
FORCEPROP 1 LAST PART_NUMBER CS11002FB07
J 0
(-11225 8625);
DISPLAY 0.489362 (-11225 8625);
PAINT BLUE (-11225 8625);
DISPLAY INVISIBLE (-11225 8625);
FORCEPROP 1 LAST MATERIAL CHIP
J 0
(-11050 8575);
DISPLAY 0.489362 (-11050 8575);
PAINT SKYBLUE (-11050 8575);
FORCEPROP 1 LAST TOLERANCE 1%
J 0
(-11125 8575);
DISPLAY 0.489362 (-11125 8575);
PAINT SKYBLUE (-11125 8575);
FORCEPROP 1 LAST VALUE 100
J 2
(-11150 8575);
DISPLAY 0.489362 (-11150 8575);
PAINT SKYBLUE (-11150 8575);
FORCEPROP 1 LAST LOCATION R1735
J 0
(-11550 8575);
DISPLAY 0.617021 (-11550 8575);
PAINT AQUA (-11550 8575);
FORCEPROP 1 LASTPIN (-11450 8575) $PN 1
J 0
(-11438 8587);
DISPLAY 0.787234 (-11438 8587);
PAINT MONO (-11438 8587);
FORCEPROP 1 LASTPIN (-11250 8575) $PN 2
J 0
(-11288 8587);
DISPLAY 0.787234 (-11288 8587);
PAINT MONO (-11288 8587);
FORCEPROP 2 LAST CDS_LIB pure_quanta
J 0
(-11350 8575);
DISPLAY INVISIBLE (-11350 8575);
FORCEPROP 1 LAST PACK_TYPE 0402LF
J 0
(-11050 8575);
DISPLAY 0.489362 (-11050 8575);
PAINT SKYBLUE (-11050 8575);
DISPLAY INVISIBLE (-11050 8575);
FORCEPROP 1 LAST WATTAGE 1/16W
J 2
(-10975 8675);
DISPLAY 0.489362 (-10975 8675);
PAINT SKYBLUE (-10975 8675);
DISPLAY INVISIBLE (-10975 8675);
FORCEPROP 1 LAST PATH I24
J 0
(-11400 8725);
DISPLAY 0.978723 (-11400 8725);
PAINT WHITE (-11400 8725);
DISPLAY INVISIBLE (-11400 8725);
FORCEPROP 0 LAST $SEC 1
J 0
(-11550 8625);
DISPLAY 0.680851 (-11550 8625);
PAINT MONO (-11550 8625);
DISPLAY INVISIBLE (-11550 8625);
FORCEPROP 0 LAST CDS_SEC 1
J 0
(-11550 8625);
DISPLAY 1.021277 (-11550 8625);
DISPLAY INVISIBLE (-11550 8625);
FORCEADD Q_RES..1
(-11350 8675);
FORCEPROP 1 LAST PART_NUMBER CS04992FB07
J 0
(-11200 8700);
DISPLAY 0.489362 (-11200 8700);
PAINT BLUE (-11200 8700);
DISPLAY INVISIBLE (-11200 8700);
FORCEPROP 1 LAST MATERIAL CHIP
J 0
(-11025 8675);
DISPLAY 0.489362 (-11025 8675);
PAINT SKYBLUE (-11025 8675);
FORCEPROP 1 LAST PACK_TYPE 0402LF
J 0
(-11200 8725);
DISPLAY 0.489362 (-11200 8725);
PAINT SKYBLUE (-11200 8725);
FORCEPROP 1 LAST VALUE 49.9
J 2
(-11150 8675);
DISPLAY 0.489362 (-11150 8675);
PAINT SKYBLUE (-11150 8675);
FORCEPROP 1 LAST WATTAGE 1/16W
J 2
(-10900 8725);
DISPLAY 0.489362 (-10900 8725);
PAINT SKYBLUE (-10900 8725);
FORCEPROP 1 LAST TOLERANCE 1%
J 0
(-11100 8675);
DISPLAY 0.489362 (-11100 8675);
PAINT SKYBLUE (-11100 8675);
FORCEPROP 1 LAST LOCATION R1717
J 0
(-11575 8675);
DISPLAY 0.574468 (-11575 8675);
PAINT AQUA (-11575 8675);
FORCEPROP 1 LASTPIN (-11450 8675) $PN 1
J 0
(-11438 8687);
DISPLAY 0.617021 (-11438 8687);
FORCEPROP 1 LASTPIN (-11250 8675) $PN 2
J 0
(-11288 8687);
DISPLAY 0.617021 (-11288 8687);
FORCEPROP 2 LAST CDS_LIB pure_quanta
J 0
(-11350 8675);
PAINT MONO (-11350 8675);
DISPLAY INVISIBLE (-11350 8675);
FORCEPROP 1 LAST PATH I25
J 0
(-11400 8825);
DISPLAY 0.978723 (-11400 8825);
PAINT WHITE (-11400 8825);
DISPLAY INVISIBLE (-11400 8825);
FORCEPROP 2 LAST $SEC 1
J 0
(-11400 8875);
DISPLAY 0.680851 (-11400 8875);
PAINT MONO (-11400 8875);
DISPLAY INVISIBLE (-11400 8875);
FORCEPROP 2 LAST CDS_SEC 1
J 0
(-11400 8875);
DISPLAY 1.021277 (-11400 8875);
DISPLAY INVISIBLE (-11400 8875);
FORCEADD OFFPAGE..6
(-10950 8350);
FORCEPROP 2 LAST $XR0 14 
J 0
(-11229 8350);
DISPLAY 0.638298 (-11229 8350);
PAINT MONO (-11229 8350);
FORCEPROP 1 LAST COMMENT_BODY TRUE
J 0
(-10850 8275);
DISPLAY 0.872340 (-10850 8275);
PAINT GREEN (-10850 8275);
DISPLAY INVISIBLE (-10850 8275);
FORCEPROP 1 LAST OFFPAGE TRUE
J 0
(-10625 8225);
DISPLAY 0.872340 (-10625 8225);
PAINT GREEN (-10625 8225);
DISPLAY INVISIBLE (-10625 8225);
FORCEPROP 2 LAST CDS_LIB standard
J 0
(-10950 8350);
DISPLAY INVISIBLE (-10950 8350);
FORCEPROP 2 LAST PATH I26
J 0
(-11225 8400);
DISPLAY 1.021277 (-11225 8400);
DISPLAY INVISIBLE (-11225 8400);
FORCEADD OFFPAGE..1
(-10950 8500);
FORCEPROP 2 LAST $XR0 14 
J 0
(-11171 8500);
DISPLAY 0.638298 (-11171 8500);
PAINT MONO (-11171 8500);
FORCEPROP 1 LAST COMMENT_BODY TRUE
J 0
(-10825 8400);
DISPLAY 0.872340 (-10825 8400);
PAINT GREEN (-10825 8400);
DISPLAY INVISIBLE (-10825 8400);
FORCEPROP 1 LAST OFFPAGE TRUE
J 0
(-10625 8375);
DISPLAY 0.872340 (-10625 8375);
PAINT GREEN (-10625 8375);
DISPLAY INVISIBLE (-10625 8375);
FORCEPROP 2 LAST CDS_LIB standard
J 0
(-10950 8500);
DISPLAY INVISIBLE (-10950 8500);
FORCEPROP 2 LAST PATH I27
J 0
(-11150 8550);
DISPLAY 1.021277 (-11150 8550);
DISPLAY INVISIBLE (-11150 8550);
FORCEADD OFFPAGE..5
(-10950 8950);
FORCEPROP 2 LAST $XR1 253 
J 0
(-11355 8950);
DISPLAY 0.638298 (-11355 8950);
PAINT MONO (-11355 8950);
FORCEPROP 2 LAST $XR0 213 
J 0
(-11235 8950);
DISPLAY 0.638298 (-11235 8950);
PAINT MONO (-11235 8950);
FORCEPROP 1 LAST COMMENT_BODY TRUE
J 0
(-10850 8875);
DISPLAY 0.872340 (-10850 8875);
PAINT GREEN (-10850 8875);
DISPLAY INVISIBLE (-10850 8875);
FORCEPROP 1 LAST OFFPAGE TRUE
J 0
(-10625 8825);
DISPLAY 0.872340 (-10625 8825);
PAINT GREEN (-10625 8825);
DISPLAY INVISIBLE (-10625 8825);
FORCEPROP 2 LAST CDS_LIB standard
J 0
(-10950 8950);
DISPLAY INVISIBLE (-10950 8950);
FORCEPROP 2 LAST PATH I28
J 0
(-11225 9000);
DISPLAY 1.021277 (-11225 9000);
DISPLAY INVISIBLE (-11225 9000);
FORCEADD OFFPAGE..1
(-10950 8800);
FORCEPROP 2 LAST $XR1 219 
J 0
(-11322 8800);
DISPLAY 0.638298 (-11322 8800);
PAINT MONO (-11322 8800);
FORCEPROP 2 LAST $XR0 214 
J 0
(-11202 8800);
DISPLAY 0.638298 (-11202 8800);
PAINT MONO (-11202 8800);
FORCEPROP 1 LAST COMMENT_BODY TRUE
J 0
(-10825 8700);
DISPLAY 0.872340 (-10825 8700);
PAINT GREEN (-10825 8700);
DISPLAY INVISIBLE (-10825 8700);
FORCEPROP 1 LAST OFFPAGE TRUE
J 0
(-10625 8675);
DISPLAY 0.872340 (-10625 8675);
PAINT GREEN (-10625 8675);
DISPLAY INVISIBLE (-10625 8675);
FORCEPROP 2 LAST CDS_LIB standard
J 0
(-10950 8800);
DISPLAY INVISIBLE (-10950 8800);
FORCEPROP 2 LAST PATH I29
J 0
(-11200 8850);
DISPLAY 1.021277 (-11200 8850);
DISPLAY INVISIBLE (-11200 8850);
FORCEADD OFFPAGE..1
(-11150 3600);
FORCEPROP 2 LAST $XR0 251 
J 0
(-11432 3600);
DISPLAY 0.638298 (-11432 3600);
PAINT MONO (-11432 3600);
FORCEPROP 1 LAST COMMENT_BODY TRUE
J 0
(-11025 3500);
DISPLAY 0.872340 (-11025 3500);
PAINT GREEN (-11025 3500);
DISPLAY INVISIBLE (-11025 3500);
FORCEPROP 1 LAST OFFPAGE TRUE
J 0
(-10825 3475);
DISPLAY 0.872340 (-10825 3475);
PAINT GREEN (-10825 3475);
DISPLAY INVISIBLE (-10825 3475);
FORCEPROP 2 LAST CDS_LIB standard
J 0
(-11150 3600);
PAINT MONO (-11150 3600);
DISPLAY INVISIBLE (-11150 3600);
FORCEPROP 2 LAST PATH I3
J 0
(-11425 3650);
DISPLAY 1.021277 (-11425 3650);
DISPLAY INVISIBLE (-11425 3650);
FORCEADD Q_RES..1
(-10525 6425);
FORCEPROP 1 LAST PART_NUMBER CS11002FB07
J 0
(-10400 6475);
DISPLAY 0.617021 (-10400 6475);
PAINT BLUE (-10400 6475);
DISPLAY INVISIBLE (-10400 6475);
FORCEPROP 1 LAST TOLERANCE 1%
J 0
(-10300 6425);
DISPLAY 0.617021 (-10300 6425);
PAINT SKYBLUE (-10300 6425);
FORCEPROP 1 LAST WATTAGE 1/16W
J 2
(-10150 6525);
DISPLAY 0.617021 (-10150 6525);
PAINT SKYBLUE (-10150 6525);
FORCEPROP 1 LAST VALUE 100
J 2
(-10325 6425);
DISPLAY 0.617021 (-10325 6425);
PAINT SKYBLUE (-10325 6425);
FORCEPROP 1 LAST MATERIAL CHIP
J 0
(-10400 6525);
DISPLAY 0.617021 (-10400 6525);
PAINT SKYBLUE (-10400 6525);
FORCEPROP 1 LAST PACK_TYPE 0402LF
J 0
(-10225 6425);
DISPLAY 0.617021 (-10225 6425);
PAINT SKYBLUE (-10225 6425);
FORCEPROP 1 LAST LOCATION PR591
J 0
(-10775 6425);
DISPLAY 0.617021 (-10775 6425);
PAINT AQUA (-10775 6425);
FORCEPROP 1 LASTPIN (-10625 6425) $PN 1
J 0
(-10613 6437);
DISPLAY 0.617021 (-10613 6437);
FORCEPROP 1 LASTPIN (-10425 6425) $PN 2
J 0
(-10463 6437);
DISPLAY 0.617021 (-10463 6437);
FORCEPROP 2 LAST CDS_LIB pure_quanta
J 0
(-10525 6425);
PAINT MONO (-10525 6425);
DISPLAY INVISIBLE (-10525 6425);
FORCEPROP 1 LAST PATH I30
J 0
(-10575 6575);
DISPLAY 0.978723 (-10575 6575);
PAINT WHITE (-10575 6575);
DISPLAY INVISIBLE (-10575 6575);
FORCEPROP 2 LAST $SEC 1
J 0
(-10575 6625);
DISPLAY 0.680851 (-10575 6625);
PAINT MONO (-10575 6625);
DISPLAY INVISIBLE (-10575 6625);
FORCEPROP 2 LAST CDS_SEC 1
J 0
(-10575 6625);
DISPLAY 1.021277 (-10575 6625);
DISPLAY INVISIBLE (-10575 6625);
FORCEADD Q_RES..1
(-10475 7100);
FORCEPROP 1 LAST PART_NUMBER CS11002FB07
J 0
(-10350 7150);
DISPLAY 0.617021 (-10350 7150);
PAINT BLUE (-10350 7150);
DISPLAY INVISIBLE (-10350 7150);
FORCEPROP 1 LAST WATTAGE 1/16W
J 2
(-10100 7200);
DISPLAY 0.617021 (-10100 7200);
PAINT SKYBLUE (-10100 7200);
FORCEPROP 1 LAST TOLERANCE 1%
J 0
(-10250 7100);
DISPLAY 0.617021 (-10250 7100);
PAINT SKYBLUE (-10250 7100);
FORCEPROP 1 LAST MATERIAL CHIP
J 0
(-10350 7200);
DISPLAY 0.617021 (-10350 7200);
PAINT SKYBLUE (-10350 7200);
FORCEPROP 1 LAST VALUE 100
J 2
(-10275 7100);
DISPLAY 0.617021 (-10275 7100);
PAINT SKYBLUE (-10275 7100);
FORCEPROP 1 LAST PACK_TYPE 0402LF
J 0
(-10175 7100);
DISPLAY 0.617021 (-10175 7100);
PAINT SKYBLUE (-10175 7100);
FORCEPROP 1 LAST LOCATION PR592
J 0
(-10725 7100);
DISPLAY 0.617021 (-10725 7100);
PAINT AQUA (-10725 7100);
FORCEPROP 1 LASTPIN (-10575 7100) $PN 1
J 0
(-10563 7112);
DISPLAY 0.617021 (-10563 7112);
FORCEPROP 1 LASTPIN (-10375 7100) $PN 2
J 0
(-10413 7112);
DISPLAY 0.617021 (-10413 7112);
FORCEPROP 2 LAST CDS_LIB pure_quanta
J 0
(-10475 7100);
PAINT MONO (-10475 7100);
DISPLAY INVISIBLE (-10475 7100);
FORCEPROP 1 LAST PATH I31
J 0
(-10525 7250);
DISPLAY 0.978723 (-10525 7250);
PAINT WHITE (-10525 7250);
DISPLAY INVISIBLE (-10525 7250);
FORCEPROP 2 LAST $SEC 1
J 0
(-10525 7300);
DISPLAY 0.680851 (-10525 7300);
PAINT MONO (-10525 7300);
DISPLAY INVISIBLE (-10525 7300);
FORCEPROP 2 LAST CDS_SEC 1
J 0
(-10525 7300);
DISPLAY 1.021277 (-10525 7300);
DISPLAY INVISIBLE (-10525 7300);
FORCEADD Q_SHORT..1
(-10550 6950);
FORCEPROP 1 LAST PART_NUMBER SHORT6
J 0
(-10525 6710);
DISPLAY 0.617021 (-10525 6710);
PAINT BLUE (-10525 6710);
DISPLAY INVISIBLE (-10525 6710);
FORCEPROP 1 LAST MATERIAL EMPTY
J 0
(-10525 6760);
DISPLAY 0.617021 (-10525 6760);
PAINT RED (-10525 6760);
FORCEPROP 2 LAST PACK_TYPE SM
J 0
(-10525 6800);
DISPLAY 0.617021 (-10525 6800);
PAINT SKYBLUE (-10525 6800);
FORCEPROP 1 LAST LOCATION PJ54
J 0
(-10650 6805);
DISPLAY 0.617021 (-10650 6805);
PAINT AQUA (-10650 6805);
FORCEPROP 0 LASTPIN (-10675 6950) $PN 1
J 2
(-10685 6960);
DISPLAY 0.617021 (-10685 6960);
PAINT MONO (-10685 6960);
FORCEPROP 0 LASTPIN (-10425 6950) $PN 2
J 0
(-10415 6960);
DISPLAY 0.617021 (-10415 6960);
PAINT MONO (-10415 6960);
FORCEPROP 2 LAST CDS_LIB pure_quanta
J 0
(-10550 6950);
DISPLAY INVISIBLE (-10550 6950);
FORCEPROP 1 LAST NEEDS_NO_SIZE TRUE
J 0
(-10550 6950);
DISPLAY 0.468085 (-10550 6950);
PAINT GREEN (-10550 6950);
DISPLAY INVISIBLE (-10550 6950);
FORCEPROP 1 LAST PATH I32
J 0
(-10625 7155);
DISPLAY 0.723404 (-10625 7155);
PAINT GREEN (-10625 7155);
DISPLAY INVISIBLE (-10625 7155);
FORCEPROP 1 LAST LOCATION PJ54
J 0
(-10625 7200);
DISPLAY 1.021277 (-10625 7200);
PAINT AQUA (-10625 7200);
DISPLAY INVISIBLE (-10625 7200);
FORCEPROP 0 LAST $SEC 1
J 0
(-10625 7200);
DISPLAY 0.680851 (-10625 7200);
PAINT MONO (-10625 7200);
DISPLAY INVISIBLE (-10625 7200);
FORCEPROP 0 LAST CDS_SEC 1
J 0
(-10625 7200);
DISPLAY 1.021277 (-10625 7200);
DISPLAY INVISIBLE (-10625 7200);
FORCEADD UNIVERSAL_GND..1
(-10000 6325);
FORCEPROP 3 LASTPIN (-10000 6375) SIG_NAME GND\g
J 0
(-9990 6385);
DISPLAY 0.659574 (-9990 6385);
PAINT MONO (-9990 6385);
DISPLAY INVISIBLE (-9990 6385);
FORCEPROP 1 LAST HDL_POWER GND
J 1
(-9975 6250);
DISPLAY 0.872340 (-9975 6250);
PAINT GREEN (-9975 6250);
DISPLAY INVISIBLE (-9975 6250);
FORCEPROP 2 LAST CDS_LIB logical_power
J 0
(-10000 6325);
PAINT MONO (-10000 6325);
DISPLAY INVISIBLE (-10000 6325);
FORCEPROP 1 LAST PATH I33
J 0
(-9925 6325);
DISPLAY 0.872340 (-9925 6325);
PAINT AQUA (-9925 6325);
DISPLAY INVISIBLE (-9925 6325);
FORCEADD VCC15..1
(-9975 7250);
FORCEPROP 3 LASTPIN (-9975 7200) SIG_NAME PVCCD_HV_CPU0\g
J 0
(-9965 7210);
DISPLAY 0.659574 (-9965 7210);
PAINT MONO (-9965 7210);
DISPLAY INVISIBLE (-9965 7210);
FORCEPROP 1 LAST HDL_POWER PVCCD_HV_CPU0
J 1
(-9975 7300);
DISPLAY 0.617021 (-9975 7300);
PAINT GREEN (-9975 7300);
FORCEPROP 2 LAST CDS_LIB logical_power
J 0
(-9975 7250);
DISPLAY INVISIBLE (-9975 7250);
FORCEPROP 1 LAST PATH I34
J 0
(-9925 7275);
DISPLAY 0.872340 (-9925 7275);
PAINT AQUA (-9925 7275);
DISPLAY INVISIBLE (-9925 7275);
FORCEADD VCC15..1
(-9600 5600);
FORCEPROP 3 LASTPIN (-9600 5550) SIG_NAME P3V3_AUX\g
J 0
(-9590 5560);
DISPLAY 0.659574 (-9590 5560);
PAINT MONO (-9590 5560);
DISPLAY INVISIBLE (-9590 5560);
FORCEPROP 1 LAST HDL_POWER P3V3_AUX
J 1
(-9600 5650);
DISPLAY 0.617021 (-9600 5650);
PAINT GREEN (-9600 5650);
FORCEPROP 2 LAST CDS_LIB logical_power
J 0
(-9600 5600);
DISPLAY INVISIBLE (-9600 5600);
FORCEPROP 1 LAST PATH I35
J 0
(-9550 5625);
DISPLAY 0.872340 (-9550 5625);
PAINT AQUA (-9550 5625);
DISPLAY INVISIBLE (-9550 5625);
FORCEADD Q_RES..1
(-9450 6950);
FORCEPROP 1 LAST PART_NUMBER CS00002JB13
J 0
(-9325 7000);
DISPLAY 0.617021 (-9325 7000);
PAINT BLUE (-9325 7000);
DISPLAY INVISIBLE (-9325 7000);
FORCEPROP 1 LAST MATERIAL CHIP
J 0
(-9325 7050);
DISPLAY 0.617021 (-9325 7050);
PAINT SKYBLUE (-9325 7050);
FORCEPROP 1 LAST WATTAGE 1/16W
J 2
(-9075 7050);
DISPLAY 0.617021 (-9075 7050);
PAINT SKYBLUE (-9075 7050);
FORCEPROP 1 LAST PACK_TYPE 0402LF
J 0
(-9200 6950);
DISPLAY 0.617021 (-9200 6950);
PAINT SKYBLUE (-9200 6950);
FORCEPROP 1 LAST VALUE 0
J 2
(-9300 6950);
DISPLAY 0.617021 (-9300 6950);
PAINT SKYBLUE (-9300 6950);
FORCEPROP 1 LAST TOLERANCE 5%
J 0
(-9275 6950);
DISPLAY 0.617021 (-9275 6950);
PAINT SKYBLUE (-9275 6950);
FORCEPROP 1 LAST LOCATION PR371
J 0
(-9700 6950);
DISPLAY 0.617021 (-9700 6950);
PAINT AQUA (-9700 6950);
FORCEPROP 1 LASTPIN (-9550 6950) $PN 1
J 0
(-9538 6962);
DISPLAY 0.617021 (-9538 6962);
PAINT MONO (-9538 6962);
FORCEPROP 1 LASTPIN (-9350 6950) $PN 2
J 0
(-9388 6962);
DISPLAY 0.617021 (-9388 6962);
PAINT MONO (-9388 6962);
FORCEPROP 2 LAST CDS_LIB pure_quanta
J 0
(-9450 6950);
DISPLAY INVISIBLE (-9450 6950);
FORCEPROP 1 LAST PATH I36
J 0
(-9500 7100);
DISPLAY 0.978723 (-9500 7100);
PAINT WHITE (-9500 7100);
DISPLAY INVISIBLE (-9500 7100);
FORCEPROP 1 LAST LOCATION PR371
J 0
(-9500 7050);
DISPLAY 1.021277 (-9500 7050);
PAINT AQUA (-9500 7050);
DISPLAY INVISIBLE (-9500 7050);
FORCEPROP 0 LAST $SEC 1
J 0
(-9500 7050);
DISPLAY 0.680851 (-9500 7050);
PAINT MONO (-9500 7050);
DISPLAY INVISIBLE (-9500 7050);
FORCEPROP 0 LAST CDS_SEC 1
J 0
(-9500 7050);
DISPLAY 1.021277 (-9500 7050);
DISPLAY INVISIBLE (-9500 7050);
FORCEADD Q_CAP..1
(-9000 6775);
FORCEPROP 1 LAST PART_NUMBER TMP_QCH2336K1B12
J 0
(-8950 6600);
DISPLAY 0.617021 (-8950 6600);
PAINT BLUE (-8950 6600);
DISPLAY INVISIBLE (-8950 6600);
FORCEPROP 1 LAST PACK_TYPE 0402
J 0
(-8950 6650);
DISPLAY 0.617021 (-8950 6650);
PAINT SKYBLUE (-8950 6650);
FORCEPROP 1 LAST VALUE 3300PF
J 0
(-8950 6850);
DISPLAY 0.617021 (-8950 6850);
PAINT SKYBLUE (-8950 6850);
FORCEPROP 1 LAST VOLTAGE 50V
J 0
(-8950 6800);
DISPLAY 0.617021 (-8950 6800);
PAINT SKYBLUE (-8950 6800);
FORCEPROP 1 LAST TOLERANCE 10%
J 0
(-8950 6750);
DISPLAY 0.617021 (-8950 6750);
PAINT SKYBLUE (-8950 6750);
FORCEPROP 1 LAST MATERIAL X7R
J 0
(-8950 6700);
DISPLAY 0.617021 (-8950 6700);
PAINT SKYBLUE (-8950 6700);
FORCEPROP 1 LAST LOCATION PC627
J 0
(-8950 6900);
DISPLAY 0.617021 (-8950 6900);
PAINT AQUA (-8950 6900);
FORCEPROP 1 LASTPIN (-9000 6875) $PN 1
J 0
(-8990 6855);
DISPLAY 0.617021 (-8990 6855);
PAINT MONO (-8990 6855);
FORCEPROP 1 LASTPIN (-9000 6675) $PN 2
J 0
(-8990 6655);
DISPLAY 0.617021 (-8990 6655);
PAINT MONO (-8990 6655);
FORCEPROP 2 LAST CDS_LIB pure_quanta
J 0
(-9000 6775);
DISPLAY INVISIBLE (-9000 6775);
FORCEPROP 1 LAST PATH I37
J 0
(-8950 6925);
DISPLAY 0.978723 (-8950 6925);
PAINT WHITE (-8950 6925);
DISPLAY INVISIBLE (-8950 6925);
FORCEPROP 1 LAST LOCATION PC627
J 0
(-8950 6900);
DISPLAY 1.021277 (-8950 6900);
PAINT AQUA (-8950 6900);
DISPLAY INVISIBLE (-8950 6900);
FORCEPROP 0 LAST $SEC 1
J 0
(-8950 6900);
DISPLAY 0.680851 (-8950 6900);
PAINT MONO (-8950 6900);
DISPLAY INVISIBLE (-8950 6900);
FORCEPROP 0 LAST CDS_SEC 1
J 0
(-8950 6900);
DISPLAY 1.021277 (-8950 6900);
DISPLAY INVISIBLE (-8950 6900);
FORCEADD Q_RES..1
(-9850 7650);
FORCEPROP 1 LAST PART_NUMBER CS00002JB13
J 0
(-9725 7700);
DISPLAY 0.617021 (-9725 7700);
PAINT BLUE (-9725 7700);
DISPLAY INVISIBLE (-9725 7700);
FORCEPROP 1 LAST MATERIAL CHIP
J 0
(-9725 7750);
DISPLAY 0.617021 (-9725 7750);
PAINT SKYBLUE (-9725 7750);
FORCEPROP 1 LAST PACK_TYPE 0402LF
J 0
(-9600 7650);
DISPLAY 0.617021 (-9600 7650);
PAINT SKYBLUE (-9600 7650);
FORCEPROP 1 LAST WATTAGE 1/16W
J 2
(-9475 7750);
DISPLAY 0.617021 (-9475 7750);
PAINT SKYBLUE (-9475 7750);
FORCEPROP 1 LAST VALUE 0
J 2
(-9700 7650);
DISPLAY 0.617021 (-9700 7650);
PAINT SKYBLUE (-9700 7650);
FORCEPROP 1 LAST TOLERANCE 5%
J 0
(-9675 7650);
DISPLAY 0.617021 (-9675 7650);
PAINT SKYBLUE (-9675 7650);
FORCEPROP 1 LAST LOCATION R2403
J 0
(-10100 7650);
DISPLAY 0.617021 (-10100 7650);
PAINT AQUA (-10100 7650);
FORCEPROP 1 LASTPIN (-9950 7650) $PN 1
J 0
(-9938 7662);
DISPLAY 0.617021 (-9938 7662);
PAINT MONO (-9938 7662);
FORCEPROP 1 LASTPIN (-9750 7650) $PN 2
J 0
(-9788 7662);
DISPLAY 0.617021 (-9788 7662);
PAINT MONO (-9788 7662);
FORCEPROP 2 LAST CDS_LIB pure_quanta
J 0
(-9850 7650);
DISPLAY INVISIBLE (-9850 7650);
FORCEPROP 1 LAST PATH I38
J 0
(-9900 7800);
DISPLAY 0.978723 (-9900 7800);
PAINT WHITE (-9900 7800);
DISPLAY INVISIBLE (-9900 7800);
FORCEPROP 1 LAST LOCATION R2403
J 0
(-9900 7750);
DISPLAY 1.021277 (-9900 7750);
PAINT AQUA (-9900 7750);
DISPLAY INVISIBLE (-9900 7750);
FORCEPROP 0 LAST $SEC 1
J 0
(-9900 7750);
DISPLAY 0.680851 (-9900 7750);
PAINT MONO (-9900 7750);
DISPLAY INVISIBLE (-9900 7750);
FORCEPROP 0 LAST CDS_SEC 1
J 0
(-9900 7750);
DISPLAY 1.021277 (-9900 7750);
DISPLAY INVISIBLE (-9900 7750);
FORCEADD Q_RES..1
(-9850 7800);
FORCEPROP 1 LAST PART_NUMBER CS00002JB13
J 0
(-9725 7850);
DISPLAY 0.617021 (-9725 7850);
PAINT BLUE (-9725 7850);
DISPLAY INVISIBLE (-9725 7850);
FORCEPROP 1 LAST PACK_TYPE 0402LF
J 0
(-9600 7800);
DISPLAY 0.617021 (-9600 7800);
PAINT SKYBLUE (-9600 7800);
FORCEPROP 1 LAST TOLERANCE 5%
J 0
(-9675 7800);
DISPLAY 0.617021 (-9675 7800);
PAINT SKYBLUE (-9675 7800);
FORCEPROP 1 LAST VALUE 0
J 2
(-9700 7800);
DISPLAY 0.617021 (-9700 7800);
PAINT SKYBLUE (-9700 7800);
FORCEPROP 1 LAST WATTAGE 1/16W
J 2
(-9475 7900);
DISPLAY 0.617021 (-9475 7900);
PAINT SKYBLUE (-9475 7900);
FORCEPROP 1 LAST MATERIAL CHIP
J 0
(-9725 7900);
DISPLAY 0.617021 (-9725 7900);
PAINT SKYBLUE (-9725 7900);
FORCEPROP 1 LAST LOCATION R2402
J 0
(-10100 7800);
DISPLAY 0.617021 (-10100 7800);
PAINT AQUA (-10100 7800);
FORCEPROP 1 LASTPIN (-9950 7800) $PN 1
J 0
(-9938 7812);
DISPLAY 0.617021 (-9938 7812);
PAINT MONO (-9938 7812);
FORCEPROP 1 LASTPIN (-9750 7800) $PN 2
J 0
(-9788 7812);
DISPLAY 0.617021 (-9788 7812);
PAINT MONO (-9788 7812);
FORCEPROP 2 LAST CDS_LIB pure_quanta
J 0
(-9850 7800);
DISPLAY INVISIBLE (-9850 7800);
FORCEPROP 1 LAST PATH I39
J 0
(-9900 7950);
DISPLAY 0.978723 (-9900 7950);
PAINT WHITE (-9900 7950);
DISPLAY INVISIBLE (-9900 7950);
FORCEPROP 1 LAST LOCATION R2402
J 0
(-9900 7900);
DISPLAY 1.021277 (-9900 7900);
PAINT AQUA (-9900 7900);
DISPLAY INVISIBLE (-9900 7900);
FORCEPROP 0 LAST $SEC 1
J 0
(-9900 7900);
DISPLAY 0.680851 (-9900 7900);
PAINT MONO (-9900 7900);
DISPLAY INVISIBLE (-9900 7900);
FORCEPROP 0 LAST CDS_SEC 1
J 0
(-9900 7900);
DISPLAY 1.021277 (-9900 7900);
DISPLAY INVISIBLE (-9900 7900);
FORCEADD UNIVERSAL_GND..1
(-11350 3650);
FORCEPROP 3 LASTPIN (-11350 3700) SIG_NAME GND\g
J 0
(-11340 3710);
DISPLAY 0.659574 (-11340 3710);
PAINT MONO (-11340 3710);
DISPLAY INVISIBLE (-11340 3710);
FORCEPROP 1 LAST HDL_POWER GND
J 1
(-11325 3575);
DISPLAY 0.872340 (-11325 3575);
PAINT GREEN (-11325 3575);
DISPLAY INVISIBLE (-11325 3575);
FORCEPROP 2 LAST CDS_LIB logical_power
J 0
(-11350 3650);
PAINT MONO (-11350 3650);
DISPLAY INVISIBLE (-11350 3650);
FORCEPROP 1 LAST PATH I4
J 0
(-11275 3650);
DISPLAY 0.872340 (-11275 3650);
PAINT AQUA (-11275 3650);
DISPLAY INVISIBLE (-11275 3650);
FORCEADD Q_RES..1
(-9850 8200);
FORCEPROP 1 LAST PART_NUMBER CS00002JB13
J 0
(-9725 8250);
DISPLAY 0.617021 (-9725 8250);
PAINT BLUE (-9725 8250);
DISPLAY INVISIBLE (-9725 8250);
FORCEPROP 1 LAST WATTAGE 1/16W
J 2
(-9475 8300);
DISPLAY 0.617021 (-9475 8300);
PAINT SKYBLUE (-9475 8300);
FORCEPROP 1 LAST MATERIAL CHIP
J 0
(-9600 8200);
DISPLAY 0.617021 (-9600 8200);
PAINT SKYBLUE (-9600 8200);
FORCEPROP 1 LAST VALUE 0
J 2
(-9700 8200);
DISPLAY 0.617021 (-9700 8200);
PAINT SKYBLUE (-9700 8200);
FORCEPROP 1 LAST PACK_TYPE 0402LF
J 0
(-9725 8300);
DISPLAY 0.617021 (-9725 8300);
PAINT SKYBLUE (-9725 8300);
FORCEPROP 1 LAST TOLERANCE 5%
J 0
(-9675 8200);
DISPLAY 0.617021 (-9675 8200);
PAINT SKYBLUE (-9675 8200);
FORCEPROP 1 LAST LOCATION R2401
J 0
(-10100 8200);
DISPLAY 0.617021 (-10100 8200);
PAINT AQUA (-10100 8200);
FORCEPROP 1 LASTPIN (-9950 8200) $PN 1
J 0
(-9938 8212);
DISPLAY 0.617021 (-9938 8212);
PAINT MONO (-9938 8212);
FORCEPROP 1 LASTPIN (-9750 8200) $PN 2
J 0
(-9788 8212);
DISPLAY 0.617021 (-9788 8212);
PAINT MONO (-9788 8212);
FORCEPROP 2 LAST CDS_LIB pure_quanta
J 0
(-9850 8200);
DISPLAY INVISIBLE (-9850 8200);
FORCEPROP 1 LAST PATH I40
J 0
(-9900 8350);
DISPLAY 0.978723 (-9900 8350);
PAINT WHITE (-9900 8350);
DISPLAY INVISIBLE (-9900 8350);
FORCEPROP 1 LAST LOCATION R2401
J 0
(-9900 8300);
DISPLAY 1.021277 (-9900 8300);
PAINT AQUA (-9900 8300);
DISPLAY INVISIBLE (-9900 8300);
FORCEPROP 0 LAST $SEC 1
J 0
(-9900 8300);
DISPLAY 0.680851 (-9900 8300);
PAINT MONO (-9900 8300);
DISPLAY INVISIBLE (-9900 8300);
FORCEPROP 0 LAST CDS_SEC 1
J 0
(-9900 8300);
DISPLAY 1.021277 (-9900 8300);
DISPLAY INVISIBLE (-9900 8300);
FORCEADD VCC15..1
(-10275 9200);
FORCEPROP 3 LASTPIN (-10275 9150) SIG_NAME P3V3_AUX\g
J 0
(-10265 9160);
DISPLAY 0.659574 (-10265 9160);
PAINT MONO (-10265 9160);
DISPLAY INVISIBLE (-10265 9160);
FORCEPROP 1 LAST HDL_POWER P3V3_AUX
J 1
(-10275 9250);
DISPLAY 0.617021 (-10275 9250);
PAINT GREEN (-10275 9250);
FORCEPROP 2 LAST CDS_LIB logical_power
J 0
(-10275 9200);
PAINT MONO (-10275 9200);
DISPLAY INVISIBLE (-10275 9200);
FORCEPROP 1 LAST PATH I41
J 0
(-10225 9225);
DISPLAY 0.872340 (-10225 9225);
PAINT AQUA (-10225 9225);
DISPLAY INVISIBLE (-10225 9225);
FORCEADD Q_RES..1
(-9850 8350);
FORCEPROP 1 LAST PART_NUMBER CS00002JB13
J 0
(-9725 8400);
DISPLAY 0.617021 (-9725 8400);
PAINT BLUE (-9725 8400);
DISPLAY INVISIBLE (-9725 8400);
FORCEPROP 1 LAST TOLERANCE 5%
J 0
(-9675 8350);
DISPLAY 0.617021 (-9675 8350);
PAINT SKYBLUE (-9675 8350);
FORCEPROP 1 LAST WATTAGE 1/16W
J 2
(-9475 8450);
DISPLAY 0.617021 (-9475 8450);
PAINT SKYBLUE (-9475 8450);
FORCEPROP 1 LAST PACK_TYPE 0402LF
J 0
(-9725 8450);
DISPLAY 0.617021 (-9725 8450);
PAINT SKYBLUE (-9725 8450);
FORCEPROP 1 LAST VALUE 0
J 2
(-9700 8350);
DISPLAY 0.617021 (-9700 8350);
PAINT SKYBLUE (-9700 8350);
FORCEPROP 1 LAST MATERIAL CHIP
J 0
(-9600 8350);
DISPLAY 0.617021 (-9600 8350);
PAINT SKYBLUE (-9600 8350);
FORCEPROP 1 LAST LOCATION R2400
J 0
(-10100 8350);
DISPLAY 0.617021 (-10100 8350);
PAINT AQUA (-10100 8350);
FORCEPROP 1 LASTPIN (-9950 8350) $PN 1
J 0
(-9938 8362);
DISPLAY 0.617021 (-9938 8362);
PAINT MONO (-9938 8362);
FORCEPROP 1 LASTPIN (-9750 8350) $PN 2
J 0
(-9788 8362);
DISPLAY 0.617021 (-9788 8362);
PAINT MONO (-9788 8362);
FORCEPROP 2 LAST CDS_LIB pure_quanta
J 0
(-9850 8350);
DISPLAY INVISIBLE (-9850 8350);
FORCEPROP 1 LAST PATH I42
J 0
(-9900 8500);
DISPLAY 0.978723 (-9900 8500);
PAINT WHITE (-9900 8500);
DISPLAY INVISIBLE (-9900 8500);
FORCEPROP 1 LAST LOCATION R2400
J 0
(-9900 8450);
DISPLAY 1.021277 (-9900 8450);
PAINT AQUA (-9900 8450);
DISPLAY INVISIBLE (-9900 8450);
FORCEPROP 0 LAST $SEC 1
J 0
(-9900 8450);
DISPLAY 0.680851 (-9900 8450);
PAINT MONO (-9900 8450);
DISPLAY INVISIBLE (-9900 8450);
FORCEPROP 0 LAST CDS_SEC 1
J 0
(-9900 8450);
DISPLAY 1.021277 (-9900 8450);
DISPLAY INVISIBLE (-9900 8450);
FORCEADD Q_RES..1
(-9850 8500);
FORCEPROP 1 LAST PART_NUMBER CS11502FB07
J 0
(-9725 8550);
DISPLAY 0.617021 (-9725 8550);
PAINT BLUE (-9725 8550);
DISPLAY INVISIBLE (-9725 8550);
FORCEPROP 1 LAST WATTAGE 1/16W
J 2
(-9475 8600);
DISPLAY 0.617021 (-9475 8600);
PAINT SKYBLUE (-9475 8600);
FORCEPROP 1 LAST PACK_TYPE 0402LF
J 0
(-9725 8600);
DISPLAY 0.617021 (-9725 8600);
PAINT SKYBLUE (-9725 8600);
FORCEPROP 1 LAST VALUE 150
J 2
(-9650 8500);
DISPLAY 0.617021 (-9650 8500);
PAINT SKYBLUE (-9650 8500);
FORCEPROP 1 LAST TOLERANCE 1%
J 0
(-9625 8500);
DISPLAY 0.617021 (-9625 8500);
PAINT SKYBLUE (-9625 8500);
FORCEPROP 1 LAST MATERIAL CHIP
J 0
(-9525 8500);
DISPLAY 0.617021 (-9525 8500);
PAINT SKYBLUE (-9525 8500);
FORCEPROP 1 LAST LOCATION R2399
J 0
(-10100 8500);
DISPLAY 0.617021 (-10100 8500);
PAINT AQUA (-10100 8500);
FORCEPROP 1 LASTPIN (-9950 8500) $PN 1
J 0
(-9938 8512);
DISPLAY 0.617021 (-9938 8512);
PAINT MONO (-9938 8512);
FORCEPROP 1 LASTPIN (-9750 8500) $PN 2
J 0
(-9788 8512);
DISPLAY 0.617021 (-9788 8512);
PAINT MONO (-9788 8512);
FORCEPROP 2 LAST CDS_LIB pure_quanta
J 0
(-9850 8500);
DISPLAY INVISIBLE (-9850 8500);
FORCEPROP 1 LAST PATH I43
J 0
(-9900 8650);
DISPLAY 0.978723 (-9900 8650);
PAINT WHITE (-9900 8650);
DISPLAY INVISIBLE (-9900 8650);
FORCEPROP 1 LAST LOCATION R2399
J 0
(-9700 8575);
DISPLAY 1.021277 (-9700 8575);
PAINT AQUA (-9700 8575);
DISPLAY INVISIBLE (-9700 8575);
FORCEPROP 0 LAST $SEC 1
J 0
(-9700 8575);
DISPLAY 0.680851 (-9700 8575);
PAINT MONO (-9700 8575);
DISPLAY INVISIBLE (-9700 8575);
FORCEPROP 0 LAST CDS_SEC 1
J 0
(-9700 8575);
DISPLAY 1.021277 (-9700 8575);
DISPLAY INVISIBLE (-9700 8575);
FORCEADD Q_RES..1
(-9850 8950);
FORCEPROP 1 LAST PART_NUMBER CS00002JB13
J 0
(-9725 9000);
DISPLAY 0.617021 (-9725 9000);
PAINT BLUE (-9725 9000);
DISPLAY INVISIBLE (-9725 9000);
FORCEPROP 1 LAST PACK_TYPE 0402LF
J 0
(-9600 8950);
DISPLAY 0.617021 (-9600 8950);
PAINT SKYBLUE (-9600 8950);
FORCEPROP 1 LAST MATERIAL CHIP
J 0
(-9725 9050);
DISPLAY 0.617021 (-9725 9050);
PAINT SKYBLUE (-9725 9050);
FORCEPROP 1 LAST TOLERANCE 5%
J 0
(-9675 8950);
DISPLAY 0.617021 (-9675 8950);
PAINT SKYBLUE (-9675 8950);
FORCEPROP 1 LAST WATTAGE 1/16W
J 2
(-9475 9050);
DISPLAY 0.617021 (-9475 9050);
PAINT SKYBLUE (-9475 9050);
FORCEPROP 1 LAST VALUE 0
J 2
(-9700 8950);
DISPLAY 0.617021 (-9700 8950);
PAINT SKYBLUE (-9700 8950);
FORCEPROP 1 LAST LOCATION R362
J 0
(-10100 8950);
DISPLAY 0.617021 (-10100 8950);
PAINT AQUA (-10100 8950);
FORCEPROP 1 LASTPIN (-9950 8950) $PN 1
J 0
(-9938 8962);
DISPLAY 0.617021 (-9938 8962);
PAINT MONO (-9938 8962);
FORCEPROP 1 LASTPIN (-9750 8950) $PN 2
J 0
(-9788 8962);
DISPLAY 0.617021 (-9788 8962);
PAINT MONO (-9788 8962);
FORCEPROP 2 LAST CDS_LIB pure_quanta
J 0
(-9850 8950);
DISPLAY INVISIBLE (-9850 8950);
FORCEPROP 1 LAST PATH I44
J 0
(-9900 9100);
DISPLAY 0.978723 (-9900 9100);
PAINT WHITE (-9900 9100);
DISPLAY INVISIBLE (-9900 9100);
FORCEPROP 1 LAST LOCATION R362
J 0
(-9900 9050);
DISPLAY 1.021277 (-9900 9050);
PAINT AQUA (-9900 9050);
DISPLAY INVISIBLE (-9900 9050);
FORCEPROP 0 LAST $SEC 1
J 0
(-9900 9050);
DISPLAY 0.680851 (-9900 9050);
PAINT MONO (-9900 9050);
DISPLAY INVISIBLE (-9900 9050);
FORCEPROP 0 LAST CDS_SEC 1
J 0
(-9900 9050);
DISPLAY 1.021277 (-9900 9050);
DISPLAY INVISIBLE (-9900 9050);
FORCEADD Q_RES..1
(-9850 8800);
FORCEPROP 1 LAST PART_NUMBER CS00002JB13
J 0
(-9725 8850);
DISPLAY 0.617021 (-9725 8850);
PAINT BLUE (-9725 8850);
DISPLAY INVISIBLE (-9725 8850);
FORCEPROP 1 LAST TOLERANCE 5%
J 0
(-9675 8800);
DISPLAY 0.617021 (-9675 8800);
PAINT SKYBLUE (-9675 8800);
FORCEPROP 1 LAST PACK_TYPE 0402LF
J 0
(-9600 8800);
DISPLAY 0.617021 (-9600 8800);
PAINT SKYBLUE (-9600 8800);
FORCEPROP 1 LAST MATERIAL CHIP
J 0
(-9725 8900);
DISPLAY 0.617021 (-9725 8900);
PAINT SKYBLUE (-9725 8900);
FORCEPROP 1 LAST VALUE 0
J 2
(-9700 8800);
DISPLAY 0.617021 (-9700 8800);
PAINT SKYBLUE (-9700 8800);
FORCEPROP 1 LAST WATTAGE 1/16W
J 2
(-9475 8900);
DISPLAY 0.617021 (-9475 8900);
PAINT SKYBLUE (-9475 8900);
FORCEPROP 1 LAST LOCATION R363
J 0
(-10100 8800);
DISPLAY 0.617021 (-10100 8800);
PAINT AQUA (-10100 8800);
FORCEPROP 1 LASTPIN (-9950 8800) $PN 1
J 0
(-9938 8812);
DISPLAY 0.617021 (-9938 8812);
PAINT MONO (-9938 8812);
FORCEPROP 1 LASTPIN (-9750 8800) $PN 2
J 0
(-9788 8812);
DISPLAY 0.617021 (-9788 8812);
PAINT MONO (-9788 8812);
FORCEPROP 2 LAST CDS_LIB pure_quanta
J 0
(-9850 8800);
DISPLAY INVISIBLE (-9850 8800);
FORCEPROP 1 LAST PATH I45
J 0
(-9900 8950);
DISPLAY 0.978723 (-9900 8950);
PAINT WHITE (-9900 8950);
DISPLAY INVISIBLE (-9900 8950);
FORCEPROP 1 LAST LOCATION R363
J 0
(-9900 8900);
DISPLAY 1.021277 (-9900 8900);
PAINT AQUA (-9900 8900);
DISPLAY INVISIBLE (-9900 8900);
FORCEPROP 0 LAST $SEC 1
J 0
(-9900 8900);
DISPLAY 0.680851 (-9900 8900);
PAINT MONO (-9900 8900);
DISPLAY INVISIBLE (-9900 8900);
FORCEPROP 0 LAST CDS_SEC 1
J 0
(-9900 8900);
DISPLAY 1.021277 (-9900 8900);
DISPLAY INVISIBLE (-9900 8900);
FORCEADD Q_RES..1
(-9850 9100);
FORCEPROP 1 LAST PART_NUMBER CS21002FB06
J 0
(-9725 9150);
DISPLAY 0.617021 (-9725 9150);
PAINT BLUE (-9725 9150);
DISPLAY INVISIBLE (-9725 9150);
FORCEPROP 1 LAST PACK_TYPE 0402LF
J 0
(-9550 9100);
DISPLAY 0.617021 (-9550 9100);
PAINT SKYBLUE (-9550 9100);
FORCEPROP 1 LAST WATTAGE 1/16W
J 2
(-9475 9200);
DISPLAY 0.617021 (-9475 9200);
PAINT SKYBLUE (-9475 9200);
FORCEPROP 1 LAST VALUE 1K
J 2
(-9675 9100);
DISPLAY 0.617021 (-9675 9100);
PAINT SKYBLUE (-9675 9100);
FORCEPROP 1 LAST TOLERANCE 1%
J 0
(-9650 9100);
DISPLAY 0.617021 (-9650 9100);
PAINT SKYBLUE (-9650 9100);
FORCEPROP 1 LAST MATERIAL CHIP
J 0
(-9725 9200);
DISPLAY 0.617021 (-9725 9200);
PAINT SKYBLUE (-9725 9200);
FORCEPROP 1 LAST LOCATION R361
J 0
(-10100 9100);
DISPLAY 0.617021 (-10100 9100);
PAINT AQUA (-10100 9100);
FORCEPROP 1 LASTPIN (-9950 9100) $PN 1
J 0
(-9938 9112);
DISPLAY 0.617021 (-9938 9112);
PAINT MONO (-9938 9112);
FORCEPROP 1 LASTPIN (-9750 9100) $PN 2
J 0
(-9788 9112);
DISPLAY 0.617021 (-9788 9112);
PAINT MONO (-9788 9112);
FORCEPROP 2 LAST CDS_LIB pure_quanta
J 0
(-9850 9100);
DISPLAY INVISIBLE (-9850 9100);
FORCEPROP 1 LAST PATH I46
J 0
(-9900 9250);
DISPLAY 0.978723 (-9900 9250);
PAINT WHITE (-9900 9250);
DISPLAY INVISIBLE (-9900 9250);
FORCEPROP 1 LAST LOCATION R361
J 0
(-9900 9200);
DISPLAY 1.021277 (-9900 9200);
PAINT AQUA (-9900 9200);
DISPLAY INVISIBLE (-9900 9200);
FORCEPROP 0 LAST $SEC 1
J 0
(-9900 9200);
DISPLAY 0.680851 (-9900 9200);
PAINT MONO (-9900 9200);
DISPLAY INVISIBLE (-9900 9200);
FORCEPROP 0 LAST CDS_SEC 1
J 0
(-9900 9200);
DISPLAY 1.021277 (-9900 9200);
DISPLAY INVISIBLE (-9900 9200);
FORCEADD Q_CAP..2
(-9000 9100);
FORCEPROP 1 LAST PART_NUMBER TMP_QCH21006JB10
J 1
(-8725 9050);
DISPLAY 0.617021 (-8725 9050);
PAINT BLUE (-8725 9050);
DISPLAY INVISIBLE (-8725 9050);
FORCEPROP 1 LAST TOLERANCE 5%
J 2
(-8350 9050);
DISPLAY 0.617021 (-8350 9050);
PAINT SKYBLUE (-8350 9050);
FORCEPROP 1 LAST PACK_TYPE 0402
J 1
(-8500 9050);
DISPLAY 0.617021 (-8500 9050);
PAINT SKYBLUE (-8500 9050);
FORCEPROP 1 LAST VALUE 1000PF
J 2
(-8675 9100);
DISPLAY 0.617021 (-8675 9100);
PAINT SKYBLUE (-8675 9100);
FORCEPROP 1 LAST VOLTAGE 50V
J 0
(-8650 9100);
DISPLAY 0.617021 (-8650 9100);
PAINT SKYBLUE (-8650 9100);
FORCEPROP 1 LAST MATERIAL EMPTY
J 0
(-8525 9100);
DISPLAY 0.617021 (-8525 9100);
PAINT RED (-8525 9100);
FORCEPROP 1 LAST LOCATION C626
J 1
(-9225 9100);
DISPLAY 0.617021 (-9225 9100);
PAINT AQUA (-9225 9100);
FORCEPROP 1 LASTPIN (-9100 9100) $PN 1
J 0
(-9110 9115);
DISPLAY 0.617021 (-9110 9115);
PAINT MONO (-9110 9115);
FORCEPROP 1 LASTPIN (-8900 9100) $PN 2
J 0
(-8915 9115);
DISPLAY 0.617021 (-8915 9115);
PAINT MONO (-8915 9115);
FORCEPROP 2 LAST CDS_LIB pure_quanta
J 0
(-9000 9100);
DISPLAY INVISIBLE (-9000 9100);
FORCEPROP 1 LAST PATH I47
J 0
(-9000 9300);
DISPLAY 0.978723 (-9000 9300);
PAINT WHITE (-9000 9300);
DISPLAY INVISIBLE (-9000 9300);
FORCEPROP 1 LAST LOCATION C626
J 0
(-9050 9200);
DISPLAY 1.021277 (-9050 9200);
PAINT AQUA (-9050 9200);
DISPLAY INVISIBLE (-9050 9200);
FORCEPROP 0 LAST $SEC 1
J 0
(-9050 9200);
DISPLAY 0.680851 (-9050 9200);
PAINT MONO (-9050 9200);
DISPLAY INVISIBLE (-9050 9200);
FORCEPROP 0 LAST CDS_SEC 1
J 0
(-9050 9200);
DISPLAY 1.021277 (-9050 9200);
DISPLAY INVISIBLE (-9050 9200);
FORCEADD Q_RES..2
R 2
(-8600 3175);
FORCEPROP 1 LAST PART_NUMBER CS21002FB06
J 2
(-8640 3050);
DISPLAY 0.617021 (-8640 3050);
PAINT BLUE (-8640 3050);
DISPLAY INVISIBLE (-8640 3050);
FORCEPROP 1 LAST PACK_TYPE 0402LF
J 2
(-8640 3000);
DISPLAY 0.617021 (-8640 3000);
PAINT SKYBLUE (-8640 3000);
FORCEPROP 1 LAST VALUE 1K
J 2
(-8645 3250);
DISPLAY 0.617021 (-8645 3250);
PAINT SKYBLUE (-8645 3250);
FORCEPROP 1 LAST MATERIAL EMPTY
J 2
(-8640 3100);
DISPLAY 0.617021 (-8640 3100);
PAINT RED (-8640 3100);
FORCEPROP 1 LAST WATTAGE 1/16W
J 2
(-8640 3150);
DISPLAY 0.617021 (-8640 3150);
PAINT SKYBLUE (-8640 3150);
FORCEPROP 1 LAST TOLERANCE 1%
J 2
(-8645 3200);
DISPLAY 0.617021 (-8645 3200);
PAINT SKYBLUE (-8645 3200);
FORCEPROP 1 LAST LOCATION PR373
J 2
(-8645 3300);
DISPLAY 0.617021 (-8645 3300);
PAINT AQUA (-8645 3300);
FORCEPROP 1 LASTPIN (-8600 3275) $PN 1
J 2
(-8605 3237);
DISPLAY 0.617021 (-8605 3237);
PAINT MONO (-8605 3237);
FORCEPROP 1 LASTPIN (-8600 3075) $PN 2
J 2
(-8605 3085);
DISPLAY 0.617021 (-8605 3085);
PAINT MONO (-8605 3085);
FORCEPROP 2 LAST CDS_LIB pure_quanta
J 2
(-8600 3175);
DISPLAY INVISIBLE (-8600 3175);
FORCEPROP 1 LAST PATH I48
J 2
(-8650 3350);
DISPLAY 0.978723 (-8650 3350);
PAINT WHITE (-8650 3350);
DISPLAY INVISIBLE (-8650 3350);
FORCEPROP 1 LAST LOCATION PR373
J 2
(-8650 3350);
DISPLAY 1.021277 (-8650 3350);
PAINT AQUA (-8650 3350);
DISPLAY INVISIBLE (-8650 3350);
FORCEPROP 0 LAST $SEC 1
J 2
(-8650 3350);
DISPLAY 0.680851 (-8650 3350);
PAINT MONO (-8650 3350);
DISPLAY INVISIBLE (-8650 3350);
FORCEPROP 0 LAST CDS_SEC 1
J 2
(-8650 3350);
DISPLAY 1.021277 (-8650 3350);
DISPLAY INVISIBLE (-8650 3350);
FORCEADD UNIVERSAL_GND..1
(-8475 2875);
FORCEPROP 3 LASTPIN (-8475 2925) SIG_NAME GND\g
J 0
(-8465 2935);
DISPLAY 0.659574 (-8465 2935);
PAINT MONO (-8465 2935);
DISPLAY INVISIBLE (-8465 2935);
FORCEPROP 1 LAST HDL_POWER GND
J 1
(-8450 2800);
DISPLAY 0.872340 (-8450 2800);
PAINT GREEN (-8450 2800);
DISPLAY INVISIBLE (-8450 2800);
FORCEPROP 2 LAST CDS_LIB logical_power
J 0
(-8475 2875);
PAINT MONO (-8475 2875);
DISPLAY INVISIBLE (-8475 2875);
FORCEPROP 1 LAST PATH I49
J 0
(-8400 2875);
DISPLAY 0.872340 (-8400 2875);
PAINT AQUA (-8400 2875);
DISPLAY INVISIBLE (-8400 2875);
FORCEADD Q_RES..1
(-10725 3850);
FORCEPROP 1 LAST PART_NUMBER CS32802FB05
J 0
(-10825 3925);
DISPLAY 0.617021 (-10825 3925);
PAINT BLUE (-10825 3925);
DISPLAY INVISIBLE (-10825 3925);
FORCEPROP 1 LAST WATTAGE 1/16W
J 2
(-10500 3975);
DISPLAY 0.617021 (-10500 3975);
PAINT SKYBLUE (-10500 3975);
FORCEPROP 1 LAST PACK_TYPE 0402LF
J 0
(-10400 3850);
DISPLAY 0.617021 (-10400 3850);
PAINT SKYBLUE (-10400 3850);
FORCEPROP 1 LAST TOLERANCE 1%
J 0
(-10475 3850);
DISPLAY 0.617021 (-10475 3850);
PAINT SKYBLUE (-10475 3850);
FORCEPROP 1 LAST VALUE 28K
J 2
(-10500 3850);
DISPLAY 0.617021 (-10500 3850);
PAINT SKYBLUE (-10500 3850);
FORCEPROP 1 LAST MATERIAL EMPTY
J 0
(-10825 3975);
DISPLAY 0.617021 (-10825 3975);
PAINT RED (-10825 3975);
FORCEPROP 1 LAST LOCATION PR357
J 0
(-10975 3850);
DISPLAY 0.617021 (-10975 3850);
PAINT AQUA (-10975 3850);
FORCEPROP 1 LASTPIN (-10825 3850) $PN 1
J 0
(-10813 3862);
DISPLAY 0.617021 (-10813 3862);
PAINT MONO (-10813 3862);
FORCEPROP 1 LASTPIN (-10625 3850) $PN 2
J 0
(-10663 3862);
DISPLAY 0.617021 (-10663 3862);
PAINT MONO (-10663 3862);
FORCEPROP 2 LAST CDS_LIB pure_quanta
J 0
(-10725 3850);
DISPLAY INVISIBLE (-10725 3850);
FORCEPROP 1 LAST PATH I5
J 0
(-10775 4000);
DISPLAY 0.978723 (-10775 4000);
PAINT WHITE (-10775 4000);
DISPLAY INVISIBLE (-10775 4000);
FORCEPROP 1 LAST LOCATION PR357
J 0
(-10800 3975);
DISPLAY 1.021277 (-10800 3975);
PAINT AQUA (-10800 3975);
DISPLAY INVISIBLE (-10800 3975);
FORCEPROP 0 LAST $SEC 1
J 0
(-10800 3975);
DISPLAY 0.680851 (-10800 3975);
PAINT MONO (-10800 3975);
DISPLAY INVISIBLE (-10800 3975);
FORCEPROP 0 LAST CDS_SEC 1
J 0
(-10800 3975);
DISPLAY 1.021277 (-10800 3975);
DISPLAY INVISIBLE (-10800 3975);
FORCEADD Q_CAP..1
(-8475 3175);
FORCEPROP 1 LAST PART_NUMBER CH4104K1B00
J 0
(-8425 3000);
DISPLAY 0.617021 (-8425 3000);
PAINT BLUE (-8425 3000);
DISPLAY INVISIBLE (-8425 3000);
FORCEPROP 1 LAST PACK_TYPE 0402
J 0
(-8425 3050);
DISPLAY 0.617021 (-8425 3050);
PAINT SKYBLUE (-8425 3050);
FORCEPROP 1 LAST VALUE 0.1UF
J 0
(-8425 3250);
DISPLAY 0.617021 (-8425 3250);
PAINT SKYBLUE (-8425 3250);
FORCEPROP 1 LAST TOLERANCE 10%
J 0
(-8425 3150);
DISPLAY 0.617021 (-8425 3150);
PAINT SKYBLUE (-8425 3150);
FORCEPROP 1 LAST MATERIAL X7R
J 0
(-8425 3100);
DISPLAY 0.617021 (-8425 3100);
PAINT SKYBLUE (-8425 3100);
FORCEPROP 1 LAST VOLTAGE 25V
J 0
(-8425 3200);
DISPLAY 0.617021 (-8425 3200);
PAINT SKYBLUE (-8425 3200);
FORCEPROP 1 LAST LOCATION PC628
J 0
(-8425 3300);
DISPLAY 0.617021 (-8425 3300);
PAINT AQUA (-8425 3300);
FORCEPROP 1 LASTPIN (-8475 3275) $PN 1
J 0
(-8465 3255);
DISPLAY 0.617021 (-8465 3255);
PAINT MONO (-8465 3255);
FORCEPROP 1 LASTPIN (-8475 3075) $PN 2
J 0
(-8465 3055);
DISPLAY 0.617021 (-8465 3055);
PAINT MONO (-8465 3055);
FORCEPROP 2 LAST CDS_LIB pure_quanta
J 0
(-8475 3175);
DISPLAY INVISIBLE (-8475 3175);
FORCEPROP 1 LAST PATH I50
J 0
(-8425 3325);
DISPLAY 0.978723 (-8425 3325);
PAINT WHITE (-8425 3325);
DISPLAY INVISIBLE (-8425 3325);
FORCEPROP 1 LAST LOCATION PC628
J 0
(-8425 3350);
DISPLAY 1.021277 (-8425 3350);
PAINT AQUA (-8425 3350);
DISPLAY INVISIBLE (-8425 3350);
FORCEPROP 0 LAST $SEC 1
J 0
(-8425 3350);
DISPLAY 0.680851 (-8425 3350);
PAINT MONO (-8425 3350);
DISPLAY INVISIBLE (-8425 3350);
FORCEPROP 0 LAST CDS_SEC 1
J 0
(-8425 3350);
DISPLAY 1.021277 (-8425 3350);
DISPLAY INVISIBLE (-8425 3350);
FORCEADD Q_CAP..2
(-8575 3550);
FORCEPROP 1 LAST PART_NUMBER CH5103KEB01
J 1
(-8350 3525);
DISPLAY 0.617021 (-8350 3525);
PAINT BLUE (-8350 3525);
DISPLAY INVISIBLE (-8350 3525);
FORCEPROP 1 LAST PACK_TYPE C0402
J 1
(-8300 3550);
DISPLAY 0.617021 (-8300 3550);
PAINT SKYBLUE (-8300 3550);
FORCEPROP 1 LAST VALUE 1UF
J 2
(-8700 3525);
DISPLAY 0.617021 (-8700 3525);
PAINT SKYBLUE (-8700 3525);
FORCEPROP 1 LAST TOLERANCE 10%
J 2
(-8350 3550);
DISPLAY 0.617021 (-8350 3550);
PAINT SKYBLUE (-8350 3550);
FORCEPROP 1 LAST MATERIAL X6S
J 0
(-8400 3575);
DISPLAY 0.617021 (-8400 3575);
PAINT SKYBLUE (-8400 3575);
FORCEPROP 1 LAST VOLTAGE 16V
J 0
(-8700 3525);
DISPLAY 0.617021 (-8700 3525);
PAINT SKYBLUE (-8700 3525);
FORCEPROP 1 LAST LOCATION PC813
J 1
(-8700 3575);
DISPLAY 0.617021 (-8700 3575);
PAINT AQUA (-8700 3575);
FORCEPROP 2 LAST CDS_LIB pure_quanta
J 0
(-8575 3550);
DISPLAY INVISIBLE (-8575 3550);
FORCEPROP 1 LAST PATH I51
J 0
(-8575 3750);
DISPLAY 0.978723 (-8575 3750);
PAINT WHITE (-8575 3750);
DISPLAY INVISIBLE (-8575 3750);
FORCEPROP 0 LAST $SEC 1
J 0
(-8400 3600);
DISPLAY INVISIBLE (-8400 3600);
FORCEPROP 0 LAST CDS_SEC 1
J 0
(-8400 3600);
DISPLAY INVISIBLE (-8400 3600);
FORCEPROP 1 LASTPIN (-8675 3550) $PN 1
J 0
(-8685 3565);
DISPLAY 0.787234 (-8685 3565);
PAINT MONO (-8685 3565);
DISPLAY INVISIBLE (-8685 3565);
FORCEPROP 1 LASTPIN (-8475 3550) $PN 2
J 0
(-8490 3565);
DISPLAY 0.787234 (-8490 3565);
PAINT MONO (-8490 3565);
DISPLAY INVISIBLE (-8490 3565);
FORCEADD UNIVERSAL_GND..1
(-8250 3275);
FORCEPROP 3 LASTPIN (-8250 3325) SIG_NAME GND\g
J 0
(-8240 3335);
DISPLAY 0.659574 (-8240 3335);
PAINT MONO (-8240 3335);
DISPLAY INVISIBLE (-8240 3335);
FORCEPROP 1 LAST HDL_POWER GND
J 1
(-8225 3200);
DISPLAY 0.872340 (-8225 3200);
PAINT GREEN (-8225 3200);
DISPLAY INVISIBLE (-8225 3200);
FORCEPROP 2 LAST CDS_LIB logical_power
J 0
(-8250 3275);
PAINT MONO (-8250 3275);
DISPLAY INVISIBLE (-8250 3275);
FORCEPROP 1 LAST PATH I52
J 0
(-8175 3275);
DISPLAY 0.872340 (-8175 3275);
PAINT AQUA (-8175 3275);
DISPLAY INVISIBLE (-8175 3275);
FORCEADD ISL69260IRAZT..1
(-7475 6200);
FORCEPROP 1 LAST PART_NUMBER AL069260000
J 0
(-8020 9145);
DISPLAY 0.617021 (-8020 9145);
PAINT BLUE (-8020 9145);
DISPLAY INVISIBLE (-8020 9145);
FORCEPROP 2 LAST VALUE ISL69260IRAZ-T
J 0
(-7525 9150);
DISPLAY 0.617021 (-7525 9150);
PAINT SKYBLUE (-7525 9150);
FORCEPROP 2 LAST PART_TYPE SMLF
J 0
(-7525 9200);
DISPLAY 0.638298 (-7525 9200);
FORCEPROP 1 LAST MATERIAL IC
J 0
(-8020 9058);
DISPLAY 0.617021 (-8020 9058);
PAINT SKYBLUE (-8020 9058);
FORCEPROP 1 LAST LOCATION PU35
J 0
(-8020 9252);
DISPLAY 0.617021 (-8020 9252);
PAINT AQUA (-8020 9252);
FORCEPROP 0 LASTPIN (-8150 3850) $PN 34
J 2
(-8160 3860);
DISPLAY 0.680851 (-8160 3860);
PAINT MONO (-8160 3860);
FORCEPROP 0 LASTPIN (-8150 4950) $PN 33
J 2
(-8160 4960);
DISPLAY 0.680851 (-8160 4960);
PAINT MONO (-8160 4960);
FORCEPROP 0 LASTPIN (-6800 4700) $PN 30
J 0
(-6790 4710);
DISPLAY 0.680851 (-6790 4710);
PAINT MONO (-6790 4710);
FORCEPROP 0 LASTPIN (-6800 5150) $PN 29
J 0
(-6790 5160);
DISPLAY 0.680851 (-6790 5160);
PAINT MONO (-6790 5160);
FORCEPROP 0 LASTPIN (-6800 5600) $PN 28
J 0
(-6790 5610);
DISPLAY 0.680851 (-6790 5610);
PAINT MONO (-6790 5610);
FORCEPROP 0 LASTPIN (-6800 6050) $PN 27
J 0
(-6790 6060);
DISPLAY 0.680851 (-6790 6060);
PAINT MONO (-6790 6060);
FORCEPROP 0 LASTPIN (-6800 6500) $PN 26
J 0
(-6790 6510);
DISPLAY 0.680851 (-6790 6510);
PAINT MONO (-6790 6510);
FORCEPROP 0 LASTPIN (-6800 6950) $PN 25
J 0
(-6790 6960);
DISPLAY 0.680851 (-6790 6960);
PAINT MONO (-6790 6960);
FORCEPROP 0 LASTPIN (-6800 7400) $PN 24
J 0
(-6790 7410);
DISPLAY 0.680851 (-6790 7410);
PAINT MONO (-6790 7410);
FORCEPROP 0 LASTPIN (-6800 7850) $PN 23
J 0
(-6790 7860);
DISPLAY 0.680851 (-6790 7860);
PAINT MONO (-6790 7860);
FORCEPROP 0 LASTPIN (-8150 8800) $PN 13
J 2
(-8160 8810);
DISPLAY 0.680851 (-8160 8810);
PAINT MONO (-8160 8810);
FORCEPROP 0 LASTPIN (-8150 4550) $PN 20
J 2
(-8160 4560);
DISPLAY 0.680851 (-8160 4560);
PAINT MONO (-8160 4560);
FORCEPROP 0 LASTPIN (-8150 8950) $PN 12
J 2
(-8160 8960);
DISPLAY 0.680851 (-8160 8960);
PAINT MONO (-8160 8960);
FORCEPROP 0 LASTPIN (-8150 4150) $PN 16
J 2
(-8160 4160);
DISPLAY 0.680851 (-8160 4160);
PAINT MONO (-8160 4160);
FORCEPROP 0 LASTPIN (-8150 7800) $PN 10
J 2
(-8160 7810);
DISPLAY 0.680851 (-8160 7810);
PAINT MONO (-8160 7810);
FORCEPROP 0 LASTPIN (-8150 7650) $PN 9
J 2
(-8160 7660);
DISPLAY 0.680851 (-8160 7660);
PAINT MONO (-8160 7660);
FORCEPROP 0 LASTPIN (-6800 4800) $PN 1
J 0
(-6790 4810);
DISPLAY 0.680851 (-6790 4810);
PAINT MONO (-6790 4810);
FORCEPROP 0 LASTPIN (-6800 5250) $PN 2
J 0
(-6790 5260);
DISPLAY 0.680851 (-6790 5260);
PAINT MONO (-6790 5260);
FORCEPROP 0 LASTPIN (-6800 5700) $PN 3
J 0
(-6790 5710);
DISPLAY 0.680851 (-6790 5710);
PAINT MONO (-6790 5710);
FORCEPROP 0 LASTPIN (-6800 6150) $PN 4
J 0
(-6790 6160);
DISPLAY 0.680851 (-6790 6160);
PAINT MONO (-6790 6160);
FORCEPROP 0 LASTPIN (-6800 6600) $PN 5
J 0
(-6790 6610);
DISPLAY 0.680851 (-6790 6610);
PAINT MONO (-6790 6610);
FORCEPROP 0 LASTPIN (-6800 7050) $PN 6
J 0
(-6790 7060);
DISPLAY 0.680851 (-6790 7060);
PAINT MONO (-6790 7060);
FORCEPROP 0 LASTPIN (-6800 7500) $PN 7
J 0
(-6790 7510);
DISPLAY 0.680851 (-6790 7510);
PAINT MONO (-6790 7510);
FORCEPROP 0 LASTPIN (-6800 7950) $PN 8
J 0
(-6790 7960);
DISPLAY 0.680851 (-6790 7960);
PAINT MONO (-6790 7960);
FORCEPROP 0 LASTPIN (-8150 6650) $PN 22
J 2
(-8160 6660);
DISPLAY 0.680851 (-8160 6660);
PAINT MONO (-8160 6660);
FORCEPROP 0 LASTPIN (-8150 5550) $PN 31
J 2
(-8160 5560);
DISPLAY 0.680851 (-8160 5560);
PAINT MONO (-8160 5560);
FORCEPROP 0 LASTPIN (-8150 8500) $PN 17
J 2
(-8160 8510);
DISPLAY 0.680851 (-8160 8510);
PAINT MONO (-8160 8510);
FORCEPROP 0 LASTPIN (-8150 8350) $PN 18
J 2
(-8160 8360);
DISPLAY 0.680851 (-8160 8360);
PAINT MONO (-8160 8360);
FORCEPROP 0 LASTPIN (-6800 3750) $PN 35
J 0
(-6790 3760);
DISPLAY 0.680851 (-6790 3760);
PAINT MONO (-6790 3760);
FORCEPROP 0 LASTPIN (-6800 4050) $PN 36
J 0
(-6790 4060);
DISPLAY 0.680851 (-6790 4060);
PAINT MONO (-6790 4060);
FORCEPROP 0 LASTPIN (-8150 3400) $PN TH
J 2
(-8160 3410);
DISPLAY 0.680851 (-8160 3410);
PAINT MONO (-8160 3410);
FORCEPROP 0 LASTPIN (-6800 8950) $PN 39
J 0
(-6790 8960);
DISPLAY 0.680851 (-6790 8960);
PAINT MONO (-6790 8960);
FORCEPROP 0 LASTPIN (-6800 8650) $PN 40
J 0
(-6790 8660);
DISPLAY 0.680851 (-6790 8660);
PAINT MONO (-6790 8660);
FORCEPROP 0 LASTPIN (-8150 6900) $PN 21
J 2
(-8160 6910);
DISPLAY 0.680851 (-8160 6910);
PAINT MONO (-8160 6910);
FORCEPROP 0 LASTPIN (-8150 5800) $PN 32
J 2
(-8160 5810);
DISPLAY 0.680851 (-8160 5810);
PAINT MONO (-8160 5810);
FORCEPROP 0 LASTPIN (-8150 4700) $PN 15
J 2
(-8160 4710);
DISPLAY 0.680851 (-8160 4710);
PAINT MONO (-8160 4710);
FORCEPROP 0 LASTPIN (-8150 7500) $PN 11
J 2
(-8160 7510);
DISPLAY 0.680851 (-8160 7510);
PAINT MONO (-8160 7510);
FORCEPROP 0 LASTPIN (-8150 8200) $PN 19
J 2
(-8160 8210);
DISPLAY 0.680851 (-8160 8210);
PAINT MONO (-8160 8210);
FORCEPROP 0 LASTPIN (-6800 4450) $PN 14
J 0
(-6790 4460);
DISPLAY 0.680851 (-6790 4460);
PAINT MONO (-6790 4460);
FORCEPROP 0 LASTPIN (-8150 3500) $PN 38
J 2
(-8160 3510);
DISPLAY 0.680851 (-8160 3510);
PAINT MONO (-8160 3510);
FORCEPROP 0 LASTPIN (-8150 3600) $PN 37
J 2
(-8160 3610);
DISPLAY 0.680851 (-8160 3610);
PAINT MONO (-8160 3610);
FORCEPROP 1 LAST PATH I53
J 0
(-7475 6200);
DISPLAY 0.723404 (-7475 6200);
PAINT GREEN (-7475 6200);
DISPLAY INVISIBLE (-7475 6200);
FORCEPROP 2 LAST CDS_LIB pure_quanta
J 0
(-7475 6200);
DISPLAY INVISIBLE (-7475 6200);
FORCEPROP 1 LAST CDS_LMAN_SYM_OUTLINE -550,2850,500,-2850
J 0
(-7475 6200);
DISPLAY 0.468085 (-7475 6200);
PAINT GREEN (-7475 6200);
DISPLAY INVISIBLE (-7475 6200);
FORCEPROP 1 LAST NEEDS_NO_SIZE TRUE
J 0
(-7475 6200);
DISPLAY 0.723404 (-7475 6200);
PAINT GREEN (-7475 6200);
DISPLAY INVISIBLE (-7475 6200);
FORCEPROP 0 LAST $SEC 1
J 0
(-8000 9300);
DISPLAY 0.680851 (-8000 9300);
PAINT MONO (-8000 9300);
DISPLAY INVISIBLE (-8000 9300);
FORCEPROP 0 LAST CDS_SEC 1
J 0
(-7975 9275);
DISPLAY 1.021277 (-7975 9275);
DISPLAY INVISIBLE (-7975 9275);
FORCEADD UNIVERSAL_GND..1
(-8300 4425);
FORCEPROP 3 LASTPIN (-8300 4475) SIG_NAME GND\g
J 0
(-8290 4485);
DISPLAY 0.659574 (-8290 4485);
PAINT MONO (-8290 4485);
DISPLAY INVISIBLE (-8290 4485);
FORCEPROP 1 LAST HDL_POWER GND
J 1
(-8275 4350);
DISPLAY 0.872340 (-8275 4350);
PAINT GREEN (-8275 4350);
DISPLAY INVISIBLE (-8275 4350);
FORCEPROP 2 LAST CDS_LIB logical_power
J 0
(-8300 4425);
PAINT MONO (-8300 4425);
DISPLAY INVISIBLE (-8300 4425);
FORCEPROP 1 LAST PATH I54
J 0
(-8225 4425);
DISPLAY 0.872340 (-8225 4425);
PAINT AQUA (-8225 4425);
DISPLAY INVISIBLE (-8225 4425);
FORCEADD UNIVERSAL_GND..1
(-5850 3325);
FORCEPROP 3 LASTPIN (-5850 3375) SIG_NAME GND\g
J 0
(-5840 3385);
DISPLAY 0.659574 (-5840 3385);
PAINT MONO (-5840 3385);
DISPLAY INVISIBLE (-5840 3385);
FORCEPROP 1 LAST HDL_POWER GND
J 1
(-5825 3250);
DISPLAY 0.872340 (-5825 3250);
PAINT GREEN (-5825 3250);
DISPLAY INVISIBLE (-5825 3250);
FORCEPROP 2 LAST CDS_LIB logical_power
J 0
(-5850 3325);
PAINT MONO (-5850 3325);
DISPLAY INVISIBLE (-5850 3325);
FORCEPROP 1 LAST PATH I55
J 0
(-5775 3325);
DISPLAY 0.872340 (-5775 3325);
PAINT AQUA (-5775 3325);
DISPLAY INVISIBLE (-5775 3325);
FORCEADD Q_CAP..1
(-5850 3550);
FORCEPROP 1 LAST PART_NUMBER TMP_QCH14706KB18
J 0
(-5800 3350);
DISPLAY 0.617021 (-5800 3350);
PAINT BLUE (-5800 3350);
DISPLAY INVISIBLE (-5800 3350);
FORCEPROP 1 LAST PACK_TYPE 0402
J 0
(-5800 3400);
DISPLAY 0.617021 (-5800 3400);
PAINT SKYBLUE (-5800 3400);
FORCEPROP 1 LAST VOLTAGE 50V
J 0
(-5800 3550);
DISPLAY 0.617021 (-5800 3550);
PAINT SKYBLUE (-5800 3550);
FORCEPROP 1 LAST VALUE 470PF
J 0
(-5800 3600);
DISPLAY 0.617021 (-5800 3600);
PAINT SKYBLUE (-5800 3600);
FORCEPROP 1 LAST TOLERANCE 10%
J 0
(-5800 3500);
DISPLAY 0.617021 (-5800 3500);
PAINT SKYBLUE (-5800 3500);
FORCEPROP 1 LAST MATERIAL X7R
J 0
(-5800 3450);
DISPLAY 0.617021 (-5800 3450);
PAINT SKYBLUE (-5800 3450);
FORCEPROP 1 LAST LOCATION PC631
J 0
(-5800 3650);
DISPLAY 0.617021 (-5800 3650);
PAINT AQUA (-5800 3650);
FORCEPROP 1 LASTPIN (-5850 3650) $PN 1
J 0
(-5840 3630);
DISPLAY 0.617021 (-5840 3630);
PAINT MONO (-5840 3630);
FORCEPROP 1 LASTPIN (-5850 3450) $PN 2
J 0
(-5840 3430);
DISPLAY 0.617021 (-5840 3430);
PAINT MONO (-5840 3430);
FORCEPROP 2 LAST CDS_LIB pure_quanta
J 0
(-5850 3550);
DISPLAY INVISIBLE (-5850 3550);
FORCEPROP 1 LAST PATH I56
J 0
(-5800 3700);
DISPLAY 0.978723 (-5800 3700);
PAINT WHITE (-5800 3700);
DISPLAY INVISIBLE (-5800 3700);
FORCEPROP 1 LAST LOCATION PC631
J 0
(-5800 3700);
DISPLAY 1.021277 (-5800 3700);
PAINT AQUA (-5800 3700);
DISPLAY INVISIBLE (-5800 3700);
FORCEPROP 0 LAST $SEC 1
J 0
(-5800 3700);
DISPLAY 0.680851 (-5800 3700);
PAINT MONO (-5800 3700);
DISPLAY INVISIBLE (-5800 3700);
FORCEPROP 0 LAST CDS_SEC 1
J 0
(-5800 3700);
DISPLAY 1.021277 (-5800 3700);
DISPLAY INVISIBLE (-5800 3700);
FORCEADD Q_RES..2
(-5150 3550);
FORCEPROP 1 LAST PART_NUMBER CS31002FB08
J 0
(-5110 3425);
DISPLAY 0.617021 (-5110 3425);
PAINT BLUE (-5110 3425);
DISPLAY INVISIBLE (-5110 3425);
FORCEPROP 1 LAST TOLERANCE 1%
J 0
(-5105 3575);
DISPLAY 0.617021 (-5105 3575);
PAINT SKYBLUE (-5105 3575);
FORCEPROP 1 LAST VALUE 10K
J 0
(-5105 3625);
DISPLAY 0.617021 (-5105 3625);
PAINT SKYBLUE (-5105 3625);
FORCEPROP 1 LAST MATERIAL EMPTY
J 0
(-5110 3475);
DISPLAY 0.617021 (-5110 3475);
PAINT RED (-5110 3475);
FORCEPROP 1 LAST PACK_TYPE 0402LF
J 0
(-5110 3375);
DISPLAY 0.617021 (-5110 3375);
PAINT SKYBLUE (-5110 3375);
FORCEPROP 1 LAST WATTAGE 1/16W
J 0
(-5110 3525);
DISPLAY 0.617021 (-5110 3525);
PAINT SKYBLUE (-5110 3525);
FORCEPROP 1 LAST LOCATION PR634
J 0
(-5105 3675);
DISPLAY 0.617021 (-5105 3675);
PAINT AQUA (-5105 3675);
FORCEPROP 2 LAST CDS_LIB pure_quanta
J 0
(-5150 3550);
DISPLAY INVISIBLE (-5150 3550);
FORCEPROP 1 LAST PATH I57
J 0
(-5100 3725);
DISPLAY 0.978723 (-5100 3725);
PAINT WHITE (-5100 3725);
DISPLAY INVISIBLE (-5100 3725);
FORCEPROP 0 LAST $SEC 1
J 0
(-5100 3725);
DISPLAY INVISIBLE (-5100 3725);
FORCEPROP 0 LAST CDS_SEC 1
J 0
(-5100 3725);
DISPLAY INVISIBLE (-5100 3725);
FORCEPROP 1 LASTPIN (-5150 3650) $PN 1
J 0
(-5145 3612);
DISPLAY 0.787234 (-5145 3612);
PAINT MONO (-5145 3612);
DISPLAY INVISIBLE (-5145 3612);
FORCEPROP 1 LASTPIN (-5150 3450) $PN 2
J 0
(-5145 3460);
DISPLAY 0.787234 (-5145 3460);
PAINT MONO (-5145 3460);
DISPLAY INVISIBLE (-5145 3460);
FORCEADD UNIVERSAL_GND..1
(-5150 3300);
FORCEPROP 3 LASTPIN (-5150 3350) SIG_NAME GND\g
J 0
(-5140 3360);
DISPLAY 0.659574 (-5140 3360);
PAINT MONO (-5140 3360);
DISPLAY INVISIBLE (-5140 3360);
FORCEPROP 1 LAST HDL_POWER GND
J 1
(-5125 3225);
DISPLAY 0.872340 (-5125 3225);
PAINT GREEN (-5125 3225);
DISPLAY INVISIBLE (-5125 3225);
FORCEPROP 2 LAST CDS_LIB logical_power
J 0
(-5150 3300);
DISPLAY INVISIBLE (-5150 3300);
FORCEPROP 1 LAST PATH I58
J 0
(-5075 3300);
DISPLAY 0.872340 (-5075 3300);
PAINT AQUA (-5075 3300);
DISPLAY INVISIBLE (-5075 3300);
FORCEADD Q_RES..1
(-4975 4050);
FORCEPROP 1 LAST PART_NUMBER CS00002JB13
J 0
(-5100 4100);
DISPLAY 0.617021 (-5100 4100);
PAINT BLUE (-5100 4100);
DISPLAY INVISIBLE (-5100 4100);
FORCEPROP 1 LAST PACK_TYPE 0402LF
J 0
(-5100 4150);
DISPLAY 0.617021 (-5100 4150);
PAINT SKYBLUE (-5100 4150);
FORCEPROP 1 LAST WATTAGE 1/16W
J 2
(-4725 4150);
DISPLAY 0.617021 (-4725 4150);
PAINT SKYBLUE (-4725 4150);
FORCEPROP 1 LAST TOLERANCE 5%
J 0
(-4775 4050);
DISPLAY 0.617021 (-4775 4050);
PAINT SKYBLUE (-4775 4050);
FORCEPROP 1 LAST VALUE 0
J 2
(-4800 4050);
DISPLAY 0.617021 (-4800 4050);
PAINT SKYBLUE (-4800 4050);
FORCEPROP 1 LAST MATERIAL CHIP
J 0
(-4700 4050);
DISPLAY 0.617021 (-4700 4050);
PAINT SKYBLUE (-4700 4050);
FORCEPROP 1 LAST LOCATION PR1311
J 0
(-5250 4050);
DISPLAY 0.617021 (-5250 4050);
PAINT AQUA (-5250 4050);
FORCEPROP 1 LASTPIN (-5075 4050) $PN 1
J 0
(-5063 4062);
DISPLAY 0.617021 (-5063 4062);
PAINT MONO (-5063 4062);
FORCEPROP 1 LASTPIN (-4875 4050) $PN 2
J 0
(-4913 4062);
DISPLAY 0.617021 (-4913 4062);
PAINT MONO (-4913 4062);
FORCEPROP 2 LAST CDS_LIB pure_quanta
J 0
(-4975 4050);
DISPLAY INVISIBLE (-4975 4050);
FORCEPROP 1 LAST PATH I59
J 0
(-5025 4200);
DISPLAY 0.978723 (-5025 4200);
PAINT WHITE (-5025 4200);
DISPLAY INVISIBLE (-5025 4200);
FORCEPROP 0 LAST $SEC 1
J 0
(-4725 4200);
DISPLAY 0.680851 (-4725 4200);
PAINT MONO (-4725 4200);
DISPLAY INVISIBLE (-4725 4200);
FORCEPROP 0 LAST CDS_SEC 1
J 0
(-4725 4200);
DISPLAY 1.021277 (-4725 4200);
DISPLAY INVISIBLE (-4725 4200);
FORCEADD Q_RES..1
(-5325 4450);
FORCEPROP 1 LAST PART_NUMBER CS00002JB13
J 0
(-5450 4500);
DISPLAY 0.617021 (-5450 4500);
PAINT BLUE (-5450 4500);
DISPLAY INVISIBLE (-5450 4500);
FORCEPROP 1 LAST WATTAGE 1/16W
J 2
(-5075 4550);
DISPLAY 0.617021 (-5075 4550);
PAINT SKYBLUE (-5075 4550);
FORCEPROP 1 LAST PACK_TYPE 0402LF
J 0
(-5450 4550);
DISPLAY 0.617021 (-5450 4550);
PAINT SKYBLUE (-5450 4550);
FORCEPROP 1 LAST VALUE 0
J 2
(-5150 4450);
DISPLAY 0.617021 (-5150 4450);
PAINT SKYBLUE (-5150 4450);
FORCEPROP 1 LAST TOLERANCE 5%
J 0
(-5125 4450);
DISPLAY 0.617021 (-5125 4450);
PAINT SKYBLUE (-5125 4450);
FORCEPROP 1 LAST MATERIAL CHIP
J 0
(-5050 4450);
DISPLAY 0.617021 (-5050 4450);
PAINT SKYBLUE (-5050 4450);
FORCEPROP 1 LAST LOCATION R2405
J 0
(-5600 4450);
DISPLAY 0.617021 (-5600 4450);
PAINT AQUA (-5600 4450);
FORCEPROP 1 LASTPIN (-5425 4450) $PN 1
J 0
(-5413 4462);
DISPLAY 0.787234 (-5413 4462);
PAINT MONO (-5413 4462);
FORCEPROP 1 LASTPIN (-5225 4450) $PN 2
J 0
(-5263 4462);
DISPLAY 0.787234 (-5263 4462);
PAINT MONO (-5263 4462);
FORCEPROP 2 LAST CDS_LIB pure_quanta
J 0
(-5325 4450);
DISPLAY INVISIBLE (-5325 4450);
FORCEPROP 1 LAST PATH I60
J 0
(-5375 4600);
DISPLAY 0.978723 (-5375 4600);
PAINT WHITE (-5375 4600);
DISPLAY INVISIBLE (-5375 4600);
FORCEPROP 0 LAST $SEC 1
J 0
(-5075 4600);
DISPLAY 0.680851 (-5075 4600);
PAINT MONO (-5075 4600);
DISPLAY INVISIBLE (-5075 4600);
FORCEPROP 0 LAST CDS_SEC 1
J 0
(-5075 4600);
DISPLAY 1.021277 (-5075 4600);
DISPLAY INVISIBLE (-5075 4600);
FORCEADD Q_RES..1
(-5200 4700);
FORCEPROP 1 LAST PART_NUMBER CS00002JB13
J 0
(-5100 4650);
DISPLAY 0.638298 (-5100 4650);
DISPLAY INVISIBLE (-5100 4650);
FORCEPROP 1 LAST PACK_TYPE 0402LF
J 0
(-4975 4700);
DISPLAY 0.638298 (-4975 4700);
FORCEPROP 1 LAST WATTAGE 1/16W
J 2
(-4625 4700);
DISPLAY 0.638298 (-4625 4700);
FORCEPROP 1 LAST TOLERANCE 5%
J 0
(-5050 4700);
DISPLAY 0.638298 (-5050 4700);
FORCEPROP 1 LAST MATERIAL CHIP
J 0
(-5400 4650);
DISPLAY 0.638298 (-5400 4650);
FORCEPROP 1 LAST VALUE 0
J 2
(-5075 4700);
DISPLAY 0.638298 (-5075 4700);
FORCEPROP 1 LAST LOCATION PR4236
J 0
(-5475 4700);
DISPLAY 0.638298 (-5475 4700);
FORCEPROP 1 LASTPIN (-5300 4700) $PN 1
J 0
(-5288 4712);
DISPLAY 0.787234 (-5288 4712);
PAINT MONO (-5288 4712);
FORCEPROP 1 LASTPIN (-5100 4700) $PN 2
J 0
(-5138 4712);
DISPLAY 0.787234 (-5138 4712);
PAINT MONO (-5138 4712);
FORCEPROP 2 LAST CDS_LIB pure_quanta
J 0
(-5200 4700);
DISPLAY INVISIBLE (-5200 4700);
FORCEPROP 1 LAST PATH I61
J 0
(-5250 4850);
DISPLAY 0.978723 (-5250 4850);
PAINT WHITE (-5250 4850);
DISPLAY INVISIBLE (-5250 4850);
FORCEPROP 0 LAST $SEC 1
J 0
(-4625 4750);
DISPLAY 0.680851 (-4625 4750);
PAINT MONO (-4625 4750);
DISPLAY INVISIBLE (-4625 4750);
FORCEPROP 0 LAST CDS_SEC 1
J 0
(-4625 4750);
DISPLAY 1.021277 (-4625 4750);
DISPLAY INVISIBLE (-4625 4750);
FORCEADD Q_RES..1
(-5200 5150);
FORCEPROP 1 LAST PART_NUMBER CS00002JB13
J 0
(-5100 5100);
DISPLAY 0.638298 (-5100 5100);
DISPLAY INVISIBLE (-5100 5100);
FORCEPROP 1 LAST PACK_TYPE 0402LF
J 0
(-4975 5150);
DISPLAY 0.638298 (-4975 5150);
FORCEPROP 1 LAST VALUE 0
J 2
(-5075 5150);
DISPLAY 0.638298 (-5075 5150);
FORCEPROP 1 LAST WATTAGE 1/16W
J 2
(-4625 5150);
DISPLAY 0.638298 (-4625 5150);
FORCEPROP 1 LAST TOLERANCE 5%
J 0
(-5050 5150);
DISPLAY 0.638298 (-5050 5150);
FORCEPROP 1 LAST MATERIAL CHIP
J 0
(-5400 5100);
DISPLAY 0.638298 (-5400 5100);
FORCEPROP 1 LAST LOCATION PR4235
J 0
(-5475 5150);
DISPLAY 0.787234 (-5475 5150);
FORCEPROP 1 LASTPIN (-5300 5150) $PN 1
J 0
(-5288 5162);
DISPLAY 0.510638 (-5288 5162);
PAINT MONO (-5288 5162);
FORCEPROP 1 LASTPIN (-5100 5150) $PN 2
J 0
(-5138 5162);
DISPLAY 0.787234 (-5138 5162);
PAINT MONO (-5138 5162);
FORCEPROP 2 LAST CDS_LIB pure_quanta
J 0
(-5200 5150);
DISPLAY INVISIBLE (-5200 5150);
FORCEPROP 1 LAST PATH I62
J 0
(-5250 5300);
DISPLAY 0.978723 (-5250 5300);
PAINT WHITE (-5250 5300);
DISPLAY INVISIBLE (-5250 5300);
FORCEPROP 0 LAST $SEC 1
J 0
(-4625 5200);
DISPLAY 0.680851 (-4625 5200);
PAINT MONO (-4625 5200);
DISPLAY INVISIBLE (-4625 5200);
FORCEPROP 0 LAST CDS_SEC 1
J 0
(-4625 5200);
DISPLAY 1.021277 (-4625 5200);
DISPLAY INVISIBLE (-4625 5200);
FORCEADD Q_RES..1
(-4875 4300);
FORCEPROP 1 LAST PART_NUMBER CS00002JB13
J 0
(-5000 4350);
DISPLAY 0.617021 (-5000 4350);
PAINT BLUE (-5000 4350);
DISPLAY INVISIBLE (-5000 4350);
FORCEPROP 1 LAST WATTAGE 1/16W
J 2
(-4625 4400);
DISPLAY 0.617021 (-4625 4400);
PAINT SKYBLUE (-4625 4400);
FORCEPROP 1 LAST MATERIAL EMPTY
J 0
(-4600 4300);
DISPLAY 0.617021 (-4600 4300);
PAINT RED (-4600 4300);
FORCEPROP 1 LAST PACK_TYPE 0402LF
J 0
(-5000 4400);
DISPLAY 0.617021 (-5000 4400);
PAINT SKYBLUE (-5000 4400);
FORCEPROP 1 LAST VALUE 0
J 2
(-4700 4300);
DISPLAY 0.617021 (-4700 4300);
PAINT SKYBLUE (-4700 4300);
FORCEPROP 1 LAST TOLERANCE 5%
J 0
(-4675 4300);
DISPLAY 0.617021 (-4675 4300);
PAINT SKYBLUE (-4675 4300);
FORCEPROP 1 LAST LOCATION PR409
J 0
(-5150 4300);
DISPLAY 0.617021 (-5150 4300);
PAINT AQUA (-5150 4300);
FORCEPROP 2 LAST CDS_LIB pure_quanta
J 0
(-4875 4300);
DISPLAY INVISIBLE (-4875 4300);
FORCEPROP 1 LAST PATH I63
J 0
(-4925 4450);
DISPLAY 0.978723 (-4925 4450);
PAINT WHITE (-4925 4450);
DISPLAY INVISIBLE (-4925 4450);
FORCEPROP 0 LAST $SEC 1
J 0
(-4625 4450);
DISPLAY INVISIBLE (-4625 4450);
FORCEPROP 0 LAST CDS_SEC 1
J 0
(-4625 4450);
DISPLAY INVISIBLE (-4625 4450);
FORCEPROP 1 LASTPIN (-4975 4300) $PN 1
J 0
(-4963 4312);
DISPLAY 0.787234 (-4963 4312);
PAINT MONO (-4963 4312);
DISPLAY INVISIBLE (-4963 4312);
FORCEPROP 1 LASTPIN (-4775 4300) $PN 2
J 0
(-4813 4312);
DISPLAY 0.787234 (-4813 4312);
PAINT MONO (-4813 4312);
DISPLAY INVISIBLE (-4813 4312);
FORCEADD UNIVERSAL_GND..1
(-8350 5350);
FORCEPROP 3 LASTPIN (-8350 5400) SIG_NAME GND\g
J 0
(-8340 5410);
DISPLAY 0.659574 (-8340 5410);
PAINT MONO (-8340 5410);
DISPLAY INVISIBLE (-8340 5410);
FORCEPROP 1 LAST HDL_POWER GND
J 1
(-8325 5275);
DISPLAY 0.872340 (-8325 5275);
PAINT GREEN (-8325 5275);
DISPLAY INVISIBLE (-8325 5275);
FORCEPROP 2 LAST CDS_LIB logical_power
J 0
(-8350 5350);
PAINT MONO (-8350 5350);
DISPLAY INVISIBLE (-8350 5350);
FORCEPROP 1 LAST PATH I64
J 0
(-8275 5350);
DISPLAY 0.872340 (-8275 5350);
PAINT AQUA (-8275 5350);
DISPLAY INVISIBLE (-8275 5350);
FORCEADD UNIVERSAL_GND..1
R 1
(-8300 9100);
FORCEPROP 3 LASTPIN (-8350 9100) SIG_NAME GND\g
J 0
(-8340 9110);
DISPLAY 0.659574 (-8340 9110);
PAINT MONO (-8340 9110);
DISPLAY INVISIBLE (-8340 9110);
FORCEPROP 1 LAST HDL_POWER GND
R 1
J 1
(-8225 9125);
DISPLAY 0.872340 (-8225 9125);
PAINT GREEN (-8225 9125);
DISPLAY INVISIBLE (-8225 9125);
FORCEPROP 2 LAST CDS_LIB logical_power
J 0
(-8300 9100);
PAINT MONO (-8300 9100);
DISPLAY INVISIBLE (-8300 9100);
FORCEPROP 1 LAST PATH I65
R 1
J 0
(-8300 9175);
DISPLAY 0.872340 (-8300 9175);
PAINT AQUA (-8300 9175);
DISPLAY INVISIBLE (-8300 9175);
FORCEADD Q_RES..1
(-5200 5600);
FORCEPROP 1 LAST PART_NUMBER CS00002JB13
J 0
(-5100 5550);
DISPLAY 0.638298 (-5100 5550);
DISPLAY INVISIBLE (-5100 5550);
FORCEPROP 1 LAST WATTAGE 1/16W
J 2
(-4625 5600);
DISPLAY 0.638298 (-4625 5600);
FORCEPROP 1 LAST TOLERANCE 5%
J 0
(-5050 5600);
DISPLAY 0.638298 (-5050 5600);
FORCEPROP 1 LAST PACK_TYPE 0402LF
J 0
(-4975 5600);
DISPLAY 0.638298 (-4975 5600);
FORCEPROP 1 LAST VALUE 0
J 2
(-5075 5600);
DISPLAY 0.638298 (-5075 5600);
FORCEPROP 1 LAST MATERIAL CHIP
J 0
(-5400 5550);
DISPLAY 0.638298 (-5400 5550);
FORCEPROP 1 LAST LOCATION PR4234
J 0
(-5425 5600);
DISPLAY 0.638298 (-5425 5600);
FORCEPROP 1 LASTPIN (-5300 5600) $PN 1
J 0
(-5288 5612);
DISPLAY 0.787234 (-5288 5612);
PAINT MONO (-5288 5612);
FORCEPROP 1 LASTPIN (-5100 5600) $PN 2
J 0
(-5138 5612);
DISPLAY 0.787234 (-5138 5612);
PAINT MONO (-5138 5612);
FORCEPROP 2 LAST CDS_LIB pure_quanta
J 0
(-5200 5600);
DISPLAY INVISIBLE (-5200 5600);
FORCEPROP 1 LAST PATH I66
J 0
(-5250 5750);
DISPLAY 0.978723 (-5250 5750);
PAINT WHITE (-5250 5750);
DISPLAY INVISIBLE (-5250 5750);
FORCEPROP 0 LAST $SEC 1
J 0
(-4625 5650);
DISPLAY 0.680851 (-4625 5650);
PAINT MONO (-4625 5650);
DISPLAY INVISIBLE (-4625 5650);
FORCEPROP 0 LAST CDS_SEC 1
J 0
(-4625 5650);
DISPLAY 1.021277 (-4625 5650);
DISPLAY INVISIBLE (-4625 5650);
FORCEADD Q_RES..1
(-5200 6050);
FORCEPROP 1 LAST PART_NUMBER CS00002JB13
J 0
(-5100 6000);
DISPLAY 0.638298 (-5100 6000);
DISPLAY INVISIBLE (-5100 6000);
FORCEPROP 1 LAST WATTAGE 1/16W
J 2
(-4625 6050);
DISPLAY 0.638298 (-4625 6050);
FORCEPROP 1 LAST PACK_TYPE 0402LF
J 0
(-4975 6050);
DISPLAY 0.638298 (-4975 6050);
FORCEPROP 1 LAST TOLERANCE 5%
J 0
(-5050 6050);
DISPLAY 0.638298 (-5050 6050);
FORCEPROP 1 LAST VALUE 0
J 2
(-5075 6050);
DISPLAY 0.638298 (-5075 6050);
FORCEPROP 1 LAST MATERIAL CHIP
J 0
(-5400 6000);
DISPLAY 0.638298 (-5400 6000);
FORCEPROP 1 LAST LOCATION PR4233
J 0
(-5425 6050);
DISPLAY 0.638298 (-5425 6050);
FORCEPROP 1 LASTPIN (-5300 6050) $PN 1
J 0
(-5288 6062);
DISPLAY 0.787234 (-5288 6062);
PAINT MONO (-5288 6062);
FORCEPROP 1 LASTPIN (-5100 6050) $PN 2
J 0
(-5138 6062);
DISPLAY 0.787234 (-5138 6062);
PAINT MONO (-5138 6062);
FORCEPROP 2 LAST CDS_LIB pure_quanta
J 0
(-5200 6050);
DISPLAY INVISIBLE (-5200 6050);
FORCEPROP 1 LAST PATH I67
J 0
(-5250 6200);
DISPLAY 0.978723 (-5250 6200);
PAINT WHITE (-5250 6200);
DISPLAY INVISIBLE (-5250 6200);
FORCEPROP 0 LAST $SEC 1
J 0
(-4625 6100);
DISPLAY 0.680851 (-4625 6100);
PAINT MONO (-4625 6100);
DISPLAY INVISIBLE (-4625 6100);
FORCEPROP 0 LAST CDS_SEC 1
J 0
(-4625 6100);
DISPLAY 1.021277 (-4625 6100);
DISPLAY INVISIBLE (-4625 6100);
FORCEADD Q_RES..1
(-5200 6500);
FORCEPROP 1 LAST PART_NUMBER CS00002JB13
J 0
(-5325 6550);
DISPLAY 0.617021 (-5325 6550);
PAINT BLUE (-5325 6550);
DISPLAY INVISIBLE (-5325 6550);
FORCEPROP 1 LAST PACK_TYPE 0402LF
J 0
(-5325 6600);
DISPLAY 0.617021 (-5325 6600);
PAINT SKYBLUE (-5325 6600);
FORCEPROP 1 LAST MATERIAL CHIP
J 0
(-4925 6500);
DISPLAY 0.617021 (-4925 6500);
PAINT SKYBLUE (-4925 6500);
FORCEPROP 1 LAST TOLERANCE 5%
J 0
(-5000 6500);
DISPLAY 0.617021 (-5000 6500);
PAINT SKYBLUE (-5000 6500);
FORCEPROP 1 LAST VALUE 0
J 2
(-5025 6500);
DISPLAY 0.617021 (-5025 6500);
PAINT SKYBLUE (-5025 6500);
FORCEPROP 1 LAST WATTAGE 1/16W
J 2
(-4950 6600);
DISPLAY 0.617021 (-4950 6600);
PAINT SKYBLUE (-4950 6600);
FORCEPROP 1 LAST LOCATION PR4232
J 0
(-5475 6500);
DISPLAY 0.617021 (-5475 6500);
PAINT AQUA (-5475 6500);
FORCEPROP 1 LASTPIN (-5300 6500) $PN 1
J 0
(-5288 6512);
DISPLAY 0.787234 (-5288 6512);
PAINT MONO (-5288 6512);
FORCEPROP 1 LASTPIN (-5100 6500) $PN 2
J 0
(-5138 6512);
DISPLAY 0.787234 (-5138 6512);
PAINT MONO (-5138 6512);
FORCEPROP 2 LAST CDS_LIB pure_quanta
J 0
(-5200 6500);
DISPLAY INVISIBLE (-5200 6500);
FORCEPROP 1 LAST PATH I68
J 0
(-5250 6650);
DISPLAY 0.978723 (-5250 6650);
PAINT WHITE (-5250 6650);
DISPLAY INVISIBLE (-5250 6650);
FORCEPROP 0 LAST $SEC 1
J 0
(-4950 6650);
DISPLAY 0.680851 (-4950 6650);
PAINT MONO (-4950 6650);
DISPLAY INVISIBLE (-4950 6650);
FORCEPROP 0 LAST CDS_SEC 1
J 0
(-4950 6650);
DISPLAY 1.021277 (-4950 6650);
DISPLAY INVISIBLE (-4950 6650);
FORCEADD Q_RES..1
(-5200 6950);
FORCEPROP 1 LAST PART_NUMBER CS00002JB13
J 0
(-5100 6900);
DISPLAY 0.638298 (-5100 6900);
DISPLAY INVISIBLE (-5100 6900);
FORCEPROP 1 LAST MATERIAL CHIP
J 0
(-5400 6900);
DISPLAY 0.638298 (-5400 6900);
FORCEPROP 1 LAST PACK_TYPE 0402LF
J 0
(-4975 6950);
DISPLAY 0.638298 (-4975 6950);
FORCEPROP 1 LAST TOLERANCE 5%
J 0
(-5050 6950);
DISPLAY 0.638298 (-5050 6950);
FORCEPROP 1 LAST VALUE 0
J 2
(-5075 6950);
DISPLAY 0.638298 (-5075 6950);
FORCEPROP 1 LAST WATTAGE 1/16W
J 2
(-4625 6950);
DISPLAY 0.638298 (-4625 6950);
FORCEPROP 1 LAST LOCATION PR4231
J 0
(-5425 6950);
DISPLAY 0.638298 (-5425 6950);
FORCEPROP 1 LASTPIN (-5300 6950) $PN 1
J 0
(-5288 6962);
DISPLAY 0.787234 (-5288 6962);
PAINT MONO (-5288 6962);
FORCEPROP 1 LASTPIN (-5100 6950) $PN 2
J 0
(-5138 6962);
DISPLAY 0.787234 (-5138 6962);
PAINT MONO (-5138 6962);
FORCEPROP 2 LAST CDS_LIB pure_quanta
J 0
(-5200 6950);
DISPLAY INVISIBLE (-5200 6950);
FORCEPROP 1 LAST PATH I69
J 0
(-5250 7100);
DISPLAY 0.978723 (-5250 7100);
PAINT WHITE (-5250 7100);
DISPLAY INVISIBLE (-5250 7100);
FORCEPROP 0 LAST $SEC 1
J 0
(-4625 7000);
DISPLAY 0.680851 (-4625 7000);
PAINT MONO (-4625 7000);
DISPLAY INVISIBLE (-4625 7000);
FORCEPROP 0 LAST CDS_SEC 1
J 0
(-4625 7000);
DISPLAY 1.021277 (-4625 7000);
DISPLAY INVISIBLE (-4625 7000);
FORCEADD Q_RES..2
R 2
(-9350 3175);
FORCEPROP 1 LAST PART_NUMBER CS21002FB06
J 2
(-9390 3050);
DISPLAY 0.617021 (-9390 3050);
PAINT BLUE (-9390 3050);
DISPLAY INVISIBLE (-9390 3050);
FORCEPROP 1 LAST PACK_TYPE 0402LF
J 2
(-9390 3000);
DISPLAY 0.617021 (-9390 3000);
PAINT SKYBLUE (-9390 3000);
FORCEPROP 1 LAST VALUE 1K
J 2
(-9395 3250);
DISPLAY 0.617021 (-9395 3250);
PAINT SKYBLUE (-9395 3250);
FORCEPROP 1 LAST TOLERANCE 1%
J 2
(-9395 3200);
DISPLAY 0.617021 (-9395 3200);
PAINT SKYBLUE (-9395 3200);
FORCEPROP 1 LAST MATERIAL EMPTY
J 2
(-9390 3100);
DISPLAY 0.617021 (-9390 3100);
PAINT RED (-9390 3100);
FORCEPROP 1 LAST WATTAGE 1/16W
J 2
(-9390 3150);
DISPLAY 0.617021 (-9390 3150);
PAINT SKYBLUE (-9390 3150);
FORCEPROP 1 LAST LOCATION PR369
J 2
(-9395 3300);
DISPLAY 0.617021 (-9395 3300);
PAINT AQUA (-9395 3300);
FORCEPROP 1 LASTPIN (-9350 3275) $PN 1
J 2
(-9355 3237);
DISPLAY 0.617021 (-9355 3237);
PAINT MONO (-9355 3237);
FORCEPROP 1 LASTPIN (-9350 3075) $PN 2
J 2
(-9355 3085);
DISPLAY 0.617021 (-9355 3085);
PAINT MONO (-9355 3085);
FORCEPROP 2 LAST CDS_LIB pure_quanta
J 2
(-9350 3175);
DISPLAY INVISIBLE (-9350 3175);
FORCEPROP 1 LAST PATH I7
J 2
(-9400 3350);
DISPLAY 0.978723 (-9400 3350);
PAINT WHITE (-9400 3350);
DISPLAY INVISIBLE (-9400 3350);
FORCEPROP 1 LAST LOCATION PR369
J 2
(-9400 3350);
DISPLAY 1.021277 (-9400 3350);
PAINT AQUA (-9400 3350);
DISPLAY INVISIBLE (-9400 3350);
FORCEPROP 0 LAST $SEC 1
J 2
(-9400 3350);
DISPLAY 0.680851 (-9400 3350);
PAINT MONO (-9400 3350);
DISPLAY INVISIBLE (-9400 3350);
FORCEPROP 0 LAST CDS_SEC 1
J 2
(-9400 3350);
DISPLAY 1.021277 (-9400 3350);
DISPLAY INVISIBLE (-9400 3350);
FORCEADD Q_CAP..1
(-6225 8275);
FORCEPROP 1 LAST PART_NUMBER CH6101MEB03
J 0
(-6175 8100);
DISPLAY 0.617021 (-6175 8100);
PAINT BLUE (-6175 8100);
DISPLAY INVISIBLE (-6175 8100);
FORCEPROP 1 LAST VOLTAGE 6.3V
J 0
(-6175 8300);
DISPLAY 0.617021 (-6175 8300);
PAINT SKYBLUE (-6175 8300);
FORCEPROP 1 LAST VALUE 10UF
J 0
(-6175 8350);
DISPLAY 0.617021 (-6175 8350);
PAINT SKYBLUE (-6175 8350);
FORCEPROP 1 LAST TOLERANCE 20%
J 0
(-6175 8250);
DISPLAY 0.617021 (-6175 8250);
PAINT SKYBLUE (-6175 8250);
FORCEPROP 1 LAST PACK_TYPE C0402
J 0
(-6175 8150);
DISPLAY 0.617021 (-6175 8150);
PAINT SKYBLUE (-6175 8150);
FORCEPROP 1 LAST MATERIAL X6S
J 0
(-6175 8200);
DISPLAY 0.617021 (-6175 8200);
PAINT SKYBLUE (-6175 8200);
FORCEPROP 1 LAST LOCATION PC630
J 0
(-6175 8400);
DISPLAY 0.617021 (-6175 8400);
PAINT AQUA (-6175 8400);
FORCEPROP 1 LASTPIN (-6225 8375) $PN 1
J 0
(-6215 8355);
DISPLAY 0.617021 (-6215 8355);
PAINT MONO (-6215 8355);
FORCEPROP 1 LASTPIN (-6225 8175) $PN 2
J 0
(-6215 8155);
DISPLAY 0.617021 (-6215 8155);
PAINT MONO (-6215 8155);
FORCEPROP 2 LAST CDS_LIB pure_quanta
J 0
(-6225 8275);
DISPLAY INVISIBLE (-6225 8275);
FORCEPROP 1 LAST PATH I70
J 0
(-6175 8425);
DISPLAY 0.978723 (-6175 8425);
PAINT WHITE (-6175 8425);
DISPLAY INVISIBLE (-6175 8425);
FORCEPROP 1 LAST LOCATION PC630
J 0
(-6175 8450);
DISPLAY 1.021277 (-6175 8450);
PAINT AQUA (-6175 8450);
DISPLAY INVISIBLE (-6175 8450);
FORCEPROP 0 LAST $SEC 1
J 0
(-6175 8450);
DISPLAY 0.680851 (-6175 8450);
PAINT MONO (-6175 8450);
DISPLAY INVISIBLE (-6175 8450);
FORCEPROP 0 LAST CDS_SEC 1
J 0
(-6175 8450);
DISPLAY 1.021277 (-6175 8450);
DISPLAY INVISIBLE (-6175 8450);
FORCEADD Q_CAP..1
(-5825 8275);
FORCEPROP 1 LAST PART_NUMBER CH5103KEB01
J 0
(-5775 8100);
DISPLAY 0.617021 (-5775 8100);
PAINT BLUE (-5775 8100);
DISPLAY INVISIBLE (-5775 8100);
FORCEPROP 1 LAST PACK_TYPE C0402
J 0
(-5775 8150);
DISPLAY 0.617021 (-5775 8150);
PAINT SKYBLUE (-5775 8150);
FORCEPROP 1 LAST MATERIAL X6S
J 0
(-5775 8200);
DISPLAY 0.617021 (-5775 8200);
PAINT SKYBLUE (-5775 8200);
FORCEPROP 1 LAST TOLERANCE 10%
J 0
(-5775 8250);
DISPLAY 0.617021 (-5775 8250);
PAINT SKYBLUE (-5775 8250);
FORCEPROP 1 LAST VOLTAGE 16V
J 0
(-5775 8300);
DISPLAY 0.617021 (-5775 8300);
PAINT SKYBLUE (-5775 8300);
FORCEPROP 1 LAST VALUE 1UF
J 0
(-5775 8350);
DISPLAY 0.617021 (-5775 8350);
PAINT SKYBLUE (-5775 8350);
FORCEPROP 1 LAST LOCATION PC1196
J 0
(-5775 8400);
DISPLAY 0.617021 (-5775 8400);
PAINT AQUA (-5775 8400);
FORCEPROP 1 LASTPIN (-5825 8375) $PN 1
J 0
(-5815 8355);
DISPLAY 0.617021 (-5815 8355);
FORCEPROP 1 LASTPIN (-5825 8175) $PN 2
J 0
(-5815 8155);
DISPLAY 0.617021 (-5815 8155);
FORCEPROP 2 LAST CDS_LIB pure_quanta
J 0
(-5825 8275);
PAINT MONO (-5825 8275);
DISPLAY INVISIBLE (-5825 8275);
FORCEPROP 1 LAST PATH I71
J 0
(-5775 8425);
DISPLAY 0.978723 (-5775 8425);
PAINT WHITE (-5775 8425);
DISPLAY INVISIBLE (-5775 8425);
FORCEPROP 2 LAST $SEC 1
J 0
(-5775 8475);
DISPLAY 0.680851 (-5775 8475);
PAINT MONO (-5775 8475);
DISPLAY INVISIBLE (-5775 8475);
FORCEPROP 2 LAST CDS_SEC 1
J 0
(-5775 8475);
DISPLAY 1.021277 (-5775 8475);
DISPLAY INVISIBLE (-5775 8475);
FORCEADD Q_CAP..1
(-6225 8750);
FORCEPROP 1 LAST PART_NUMBER CH4106K1B01
J 0
(-6175 8575);
DISPLAY 0.617021 (-6175 8575);
PAINT BLUE (-6175 8575);
DISPLAY INVISIBLE (-6175 8575);
FORCEPROP 1 LAST VOLTAGE 50V
J 0
(-6175 8775);
DISPLAY 0.617021 (-6175 8775);
PAINT SKYBLUE (-6175 8775);
FORCEPROP 1 LAST TOLERANCE 10%
J 0
(-6175 8725);
DISPLAY 0.617021 (-6175 8725);
PAINT SKYBLUE (-6175 8725);
FORCEPROP 1 LAST VALUE 100NF
J 0
(-6175 8825);
DISPLAY 0.617021 (-6175 8825);
PAINT SKYBLUE (-6175 8825);
FORCEPROP 1 LAST PACK_TYPE C0402
J 0
(-6175 8625);
DISPLAY 0.617021 (-6175 8625);
PAINT SKYBLUE (-6175 8625);
FORCEPROP 1 LAST MATERIAL EMPTY
J 0
(-6175 8675);
DISPLAY 0.617021 (-6175 8675);
PAINT RED (-6175 8675);
FORCEPROP 1 LAST LOCATION PC629
J 0
(-6175 8875);
DISPLAY 0.617021 (-6175 8875);
PAINT AQUA (-6175 8875);
FORCEPROP 1 LASTPIN (-6225 8850) $PN 1
J 0
(-6215 8830);
DISPLAY 0.617021 (-6215 8830);
PAINT MONO (-6215 8830);
FORCEPROP 1 LASTPIN (-6225 8650) $PN 2
J 0
(-6215 8630);
DISPLAY 0.617021 (-6215 8630);
PAINT MONO (-6215 8630);
FORCEPROP 2 LAST CDS_LIB pure_quanta
J 0
(-6225 8750);
DISPLAY INVISIBLE (-6225 8750);
FORCEPROP 1 LAST PATH I72
J 0
(-6175 8900);
DISPLAY 0.978723 (-6175 8900);
PAINT WHITE (-6175 8900);
DISPLAY INVISIBLE (-6175 8900);
FORCEPROP 1 LAST LOCATION PC629
J 0
(-6175 8925);
DISPLAY 1.021277 (-6175 8925);
PAINT AQUA (-6175 8925);
DISPLAY INVISIBLE (-6175 8925);
FORCEPROP 0 LAST $SEC 1
J 0
(-6175 8925);
DISPLAY 0.680851 (-6175 8925);
PAINT MONO (-6175 8925);
DISPLAY INVISIBLE (-6175 8925);
FORCEPROP 0 LAST CDS_SEC 1
J 0
(-6175 8925);
DISPLAY 1.021277 (-6175 8925);
DISPLAY INVISIBLE (-6175 8925);
FORCEADD Q_CAP..1
(-5825 8750);
FORCEPROP 1 LAST PART_NUMBER CH5103KEB01
J 0
(-5775 8575);
DISPLAY 0.617021 (-5775 8575);
PAINT BLUE (-5775 8575);
DISPLAY INVISIBLE (-5775 8575);
FORCEPROP 1 LAST MATERIAL X6S
J 0
(-5775 8675);
DISPLAY 0.617021 (-5775 8675);
PAINT SKYBLUE (-5775 8675);
FORCEPROP 1 LAST VOLTAGE 16V
J 0
(-5775 8775);
DISPLAY 0.617021 (-5775 8775);
PAINT SKYBLUE (-5775 8775);
FORCEPROP 1 LAST VALUE 1UF
J 0
(-5775 8825);
DISPLAY 0.617021 (-5775 8825);
PAINT SKYBLUE (-5775 8825);
FORCEPROP 1 LAST TOLERANCE 10%
J 0
(-5775 8725);
DISPLAY 0.617021 (-5775 8725);
PAINT SKYBLUE (-5775 8725);
FORCEPROP 1 LAST PACK_TYPE C0402
J 0
(-5775 8625);
DISPLAY 0.617021 (-5775 8625);
PAINT SKYBLUE (-5775 8625);
FORCEPROP 1 LAST LOCATION PC632
J 0
(-5775 8875);
DISPLAY 0.617021 (-5775 8875);
PAINT AQUA (-5775 8875);
FORCEPROP 1 LASTPIN (-5825 8850) $PN 1
J 0
(-5815 8830);
DISPLAY 0.617021 (-5815 8830);
PAINT MONO (-5815 8830);
FORCEPROP 1 LASTPIN (-5825 8650) $PN 2
J 0
(-5815 8630);
DISPLAY 0.617021 (-5815 8630);
PAINT MONO (-5815 8630);
FORCEPROP 2 LAST CDS_LIB pure_quanta
J 0
(-5825 8750);
DISPLAY INVISIBLE (-5825 8750);
FORCEPROP 1 LAST PATH I73
J 0
(-5775 8900);
DISPLAY 0.978723 (-5775 8900);
PAINT WHITE (-5775 8900);
DISPLAY INVISIBLE (-5775 8900);
FORCEPROP 1 LAST LOCATION PC632
J 0
(-5775 8925);
DISPLAY 1.021277 (-5775 8925);
PAINT AQUA (-5775 8925);
DISPLAY INVISIBLE (-5775 8925);
FORCEPROP 0 LAST $SEC 1
J 0
(-5775 8925);
DISPLAY 0.680851 (-5775 8925);
PAINT MONO (-5775 8925);
DISPLAY INVISIBLE (-5775 8925);
FORCEPROP 0 LAST CDS_SEC 1
J 0
(-5775 8925);
DISPLAY 1.021277 (-5775 8925);
DISPLAY INVISIBLE (-5775 8925);
FORCEADD Q_RES..1
(-5200 7400);
FORCEPROP 1 LAST PART_NUMBER CS00002JB13
J 0
(-5100 7350);
DISPLAY 0.638298 (-5100 7350);
DISPLAY INVISIBLE (-5100 7350);
FORCEPROP 1 LAST TOLERANCE 5%
J 0
(-5050 7400);
DISPLAY 0.638298 (-5050 7400);
FORCEPROP 1 LAST VALUE 0
J 2
(-5075 7400);
DISPLAY 0.638298 (-5075 7400);
FORCEPROP 1 LAST MATERIAL CHIP
J 0
(-5400 7350);
DISPLAY 0.638298 (-5400 7350);
FORCEPROP 1 LAST WATTAGE 1/16W
J 2
(-4625 7400);
DISPLAY 0.638298 (-4625 7400);
FORCEPROP 1 LAST PACK_TYPE 0402LF
J 0
(-4975 7400);
DISPLAY 0.638298 (-4975 7400);
FORCEPROP 1 LAST LOCATION PR4230
J 0
(-5450 7400);
DISPLAY 0.638298 (-5450 7400);
FORCEPROP 1 LASTPIN (-5300 7400) $PN 1
J 0
(-5288 7412);
DISPLAY 0.787234 (-5288 7412);
PAINT MONO (-5288 7412);
FORCEPROP 1 LASTPIN (-5100 7400) $PN 2
J 0
(-5138 7412);
DISPLAY 0.787234 (-5138 7412);
PAINT MONO (-5138 7412);
FORCEPROP 2 LAST CDS_LIB pure_quanta
J 0
(-5200 7400);
DISPLAY INVISIBLE (-5200 7400);
FORCEPROP 1 LAST PATH I74
J 0
(-5250 7550);
DISPLAY 0.978723 (-5250 7550);
PAINT WHITE (-5250 7550);
DISPLAY INVISIBLE (-5250 7550);
FORCEPROP 0 LAST $SEC 1
J 0
(-4625 7450);
DISPLAY 0.680851 (-4625 7450);
PAINT MONO (-4625 7450);
DISPLAY INVISIBLE (-4625 7450);
FORCEPROP 0 LAST CDS_SEC 1
J 0
(-4625 7450);
DISPLAY 1.021277 (-4625 7450);
DISPLAY INVISIBLE (-4625 7450);
FORCEADD OFFPAGE..2
(-5525 7950);
FORCEPROP 2 LAST $XR0 279 
J 0
(-5336 7950);
DISPLAY 0.638298 (-5336 7950);
PAINT MONO (-5336 7950);
FORCEPROP 1 LAST COMMENT_BODY TRUE
J 0
(-5570 7855);
DISPLAY 0.872340 (-5570 7855);
PAINT GREEN (-5570 7855);
DISPLAY INVISIBLE (-5570 7855);
FORCEPROP 1 LAST OFFPAGE TRUE
J 0
(-5200 7825);
DISPLAY 0.872340 (-5200 7825);
PAINT GREEN (-5200 7825);
DISPLAY INVISIBLE (-5200 7825);
FORCEPROP 2 LAST CDS_LIB standard
J 0
(-5525 7950);
DISPLAY INVISIBLE (-5525 7950);
FORCEPROP 2 LAST PATH I75
J 0
(-5325 8000);
DISPLAY 1.021277 (-5325 8000);
DISPLAY INVISIBLE (-5325 8000);
FORCEADD OFFPAGE..4
(-5525 7850);
FORCEPROP 2 LAST $XR0 279 
J 0
(-5339 7850);
DISPLAY 0.638298 (-5339 7850);
PAINT MONO (-5339 7850);
FORCEPROP 1 LAST COMMENT_BODY TRUE
J 0
(-5550 7750);
DISPLAY 0.872340 (-5550 7750);
PAINT GREEN (-5550 7750);
DISPLAY INVISIBLE (-5550 7750);
FORCEPROP 1 LAST OFFPAGE TRUE
J 0
(-5200 7725);
DISPLAY 0.872340 (-5200 7725);
PAINT GREEN (-5200 7725);
DISPLAY INVISIBLE (-5200 7725);
FORCEPROP 2 LAST CDS_LIB standard
J 0
(-5525 7850);
DISPLAY INVISIBLE (-5525 7850);
FORCEPROP 2 LAST PATH I76
J 0
(-5325 7900);
DISPLAY 1.021277 (-5325 7900);
DISPLAY INVISIBLE (-5325 7900);
FORCEADD UNIVERSAL_GND..1
R 3
(-5375 8075);
FORCEPROP 3 LASTPIN (-5425 8075) SIG_NAME GND\g
J 0
(-5415 8085);
DISPLAY 0.659574 (-5415 8085);
PAINT MONO (-5415 8085);
DISPLAY INVISIBLE (-5415 8085);
FORCEPROP 1 LAST HDL_POWER GND
R 1
J 1
(-5300 8050);
DISPLAY 0.872340 (-5300 8050);
PAINT GREEN (-5300 8050);
DISPLAY INVISIBLE (-5300 8050);
FORCEPROP 2 LAST CDS_LIB logical_power
J 0
(-5375 8075);
PAINT MONO (-5375 8075);
DISPLAY INVISIBLE (-5375 8075);
FORCEPROP 1 LAST PATH I77
R 1
J 2
(-5375 8000);
DISPLAY 0.872340 (-5375 8000);
PAINT AQUA (-5375 8000);
DISPLAY INVISIBLE (-5375 8000);
FORCEADD UNIVERSAL_GND..1
R 3
(-5375 8550);
FORCEPROP 3 LASTPIN (-5425 8550) SIG_NAME GND\g
J 0
(-5415 8560);
DISPLAY 0.659574 (-5415 8560);
PAINT MONO (-5415 8560);
DISPLAY INVISIBLE (-5415 8560);
FORCEPROP 1 LAST HDL_POWER GND
R 1
J 1
(-5300 8525);
DISPLAY 0.872340 (-5300 8525);
PAINT GREEN (-5300 8525);
DISPLAY INVISIBLE (-5300 8525);
FORCEPROP 2 LAST CDS_LIB logical_power
J 0
(-5375 8550);
PAINT MONO (-5375 8550);
DISPLAY INVISIBLE (-5375 8550);
FORCEPROP 1 LAST PATH I78
R 1
J 2
(-5375 8475);
DISPLAY 0.872340 (-5375 8475);
PAINT AQUA (-5375 8475);
DISPLAY INVISIBLE (-5375 8475);
FORCEADD OFFPAGE..2
(-5375 8475);
FORCEPROP 2 LAST $XR1 279 
J 0
(-5066 8475);
DISPLAY 0.638298 (-5066 8475);
PAINT MONO (-5066 8475);
FORCEPROP 2 LAST $XR0 278 
J 0
(-5186 8475);
DISPLAY 0.638298 (-5186 8475);
PAINT MONO (-5186 8475);
FORCEPROP 1 LAST COMMENT_BODY TRUE
J 0
(-5420 8380);
DISPLAY 0.872340 (-5420 8380);
PAINT GREEN (-5420 8380);
DISPLAY INVISIBLE (-5420 8380);
FORCEPROP 1 LAST OFFPAGE TRUE
J 0
(-5050 8350);
DISPLAY 0.872340 (-5050 8350);
PAINT GREEN (-5050 8350);
DISPLAY INVISIBLE (-5050 8350);
FORCEPROP 2 LAST CDS_LIB standard
J 0
(-5375 8475);
DISPLAY INVISIBLE (-5375 8475);
FORCEPROP 2 LAST PATH I79
J 0
(-5050 8525);
DISPLAY 1.021277 (-5050 8525);
DISPLAY INVISIBLE (-5050 8525);
FORCEADD UNIVERSAL_GND..1
(-9225 2875);
FORCEPROP 3 LASTPIN (-9225 2925) SIG_NAME GND\g
J 0
(-9215 2935);
DISPLAY 0.659574 (-9215 2935);
PAINT MONO (-9215 2935);
DISPLAY INVISIBLE (-9215 2935);
FORCEPROP 1 LAST HDL_POWER GND
J 1
(-9200 2800);
DISPLAY 0.872340 (-9200 2800);
PAINT GREEN (-9200 2800);
DISPLAY INVISIBLE (-9200 2800);
FORCEPROP 2 LAST CDS_LIB logical_power
J 0
(-9225 2875);
PAINT MONO (-9225 2875);
DISPLAY INVISIBLE (-9225 2875);
FORCEPROP 1 LAST PATH I8
J 0
(-9150 2875);
DISPLAY 0.872340 (-9150 2875);
PAINT AQUA (-9150 2875);
DISPLAY INVISIBLE (-9150 2875);
FORCEADD Q_RES..1
(-5500 8950);
FORCEPROP 1 LAST PART_NUMBER CS-1002FB04
J 0
(-5350 8900);
DISPLAY 0.617021 (-5350 8900);
PAINT BLUE (-5350 8900);
DISPLAY INVISIBLE (-5350 8900);
FORCEPROP 1 LAST VALUE 1
J 2
(-5325 8950);
DISPLAY 0.617021 (-5325 8950);
PAINT SKYBLUE (-5325 8950);
FORCEPROP 1 LAST TOLERANCE 1%
J 0
(-5300 8950);
DISPLAY 0.617021 (-5300 8950);
PAINT SKYBLUE (-5300 8950);
FORCEPROP 1 LAST MATERIAL CHIP
J 0
(-5200 8950);
DISPLAY 0.617021 (-5200 8950);
PAINT SKYBLUE (-5200 8950);
FORCEPROP 1 LAST WATTAGE 1/16W
J 2
(-5050 8850);
DISPLAY 0.617021 (-5050 8850);
PAINT SKYBLUE (-5050 8850);
FORCEPROP 1 LAST PACK_TYPE 0402LF
J 0
(-5350 8850);
DISPLAY 0.617021 (-5350 8850);
PAINT SKYBLUE (-5350 8850);
FORCEPROP 1 LAST LOCATION PR375
J 0
(-5725 8950);
DISPLAY 0.617021 (-5725 8950);
PAINT AQUA (-5725 8950);
FORCEPROP 1 LASTPIN (-5600 8950) $PN 1
J 0
(-5588 8962);
DISPLAY 0.617021 (-5588 8962);
PAINT MONO (-5588 8962);
FORCEPROP 1 LASTPIN (-5400 8950) $PN 2
J 0
(-5438 8962);
DISPLAY 0.617021 (-5438 8962);
PAINT MONO (-5438 8962);
FORCEPROP 2 LAST CDS_LIB pure_quanta
J 0
(-5500 8950);
DISPLAY INVISIBLE (-5500 8950);
FORCEPROP 1 LAST PATH I80
J 0
(-5550 9100);
DISPLAY 0.978723 (-5550 9100);
PAINT WHITE (-5550 9100);
DISPLAY INVISIBLE (-5550 9100);
FORCEPROP 1 LAST LOCATION PR375
J 0
(-5550 9050);
DISPLAY 1.021277 (-5550 9050);
PAINT AQUA (-5550 9050);
DISPLAY INVISIBLE (-5550 9050);
FORCEPROP 0 LAST $SEC 1
J 0
(-5550 9050);
DISPLAY 0.680851 (-5550 9050);
PAINT MONO (-5550 9050);
DISPLAY INVISIBLE (-5550 9050);
FORCEPROP 0 LAST CDS_SEC 1
J 0
(-5550 9050);
DISPLAY 1.021277 (-5550 9050);
DISPLAY INVISIBLE (-5550 9050);
FORCEADD VCC15..1
(-5025 9075);
FORCEPROP 3 LASTPIN (-5025 9025) SIG_NAME P3V3_AUX\g
J 0
(-5015 9035);
DISPLAY 0.659574 (-5015 9035);
PAINT MONO (-5015 9035);
DISPLAY INVISIBLE (-5015 9035);
FORCEPROP 1 LAST HDL_POWER P3V3_AUX
J 1
(-5025 9125);
DISPLAY 0.617021 (-5025 9125);
PAINT GREEN (-5025 9125);
FORCEPROP 2 LAST CDS_LIB logical_power
J 0
(-5025 9075);
DISPLAY INVISIBLE (-5025 9075);
FORCEPROP 1 LAST PATH I81
J 0
(-4975 9100);
DISPLAY 0.872340 (-4975 9100);
PAINT AQUA (-4975 9100);
DISPLAY INVISIBLE (-4975 9100);
FORCEADD OFFPAGE..4
(-3975 3750);
FORCEPROP 2 LAST $XR0 279 
J 0
(-3789 3750);
DISPLAY 0.638298 (-3789 3750);
PAINT MONO (-3789 3750);
FORCEPROP 1 LAST COMMENT_BODY TRUE
J 0
(-4000 3650);
DISPLAY 0.872340 (-4000 3650);
PAINT GREEN (-4000 3650);
DISPLAY INVISIBLE (-4000 3650);
FORCEPROP 1 LAST OFFPAGE TRUE
J 0
(-3650 3625);
DISPLAY 0.872340 (-3650 3625);
PAINT GREEN (-3650 3625);
DISPLAY INVISIBLE (-3650 3625);
FORCEPROP 2 LAST CDS_LIB standard
J 0
(-3975 3750);
DISPLAY INVISIBLE (-3975 3750);
FORCEPROP 2 LAST PATH I82
J 0
(-3775 3800);
DISPLAY 1.021277 (-3775 3800);
DISPLAY INVISIBLE (-3775 3800);
FORCEADD UNIVERSAL_GND..1
(-4100 3925);
FORCEPROP 3 LASTPIN (-4100 3975) SIG_NAME GND\g
J 0
(-4090 3985);
DISPLAY 0.659574 (-4090 3985);
PAINT MONO (-4090 3985);
DISPLAY INVISIBLE (-4090 3985);
FORCEPROP 1 LAST HDL_POWER GND
J 1
(-4075 3850);
DISPLAY 0.872340 (-4075 3850);
PAINT GREEN (-4075 3850);
DISPLAY INVISIBLE (-4075 3850);
FORCEPROP 2 LAST CDS_LIB logical_power
J 0
(-4100 3925);
PAINT MONO (-4100 3925);
DISPLAY INVISIBLE (-4100 3925);
FORCEPROP 1 LAST PATH I83
J 0
(-4025 3925);
DISPLAY 0.872340 (-4025 3925);
PAINT AQUA (-4025 3925);
DISPLAY INVISIBLE (-4025 3925);
FORCEADD UNIVERSAL_GND..1
(-4575 4625);
FORCEPROP 3 LASTPIN (-4575 4675) SIG_NAME GND\g
J 0
(-4565 4685);
DISPLAY 0.659574 (-4565 4685);
PAINT MONO (-4565 4685);
DISPLAY INVISIBLE (-4565 4685);
FORCEPROP 1 LAST HDL_POWER GND
J 1
(-4550 4550);
DISPLAY 0.872340 (-4550 4550);
PAINT GREEN (-4550 4550);
DISPLAY INVISIBLE (-4550 4550);
FORCEPROP 2 LAST CDS_LIB logical_power
J 0
(-4575 4625);
DISPLAY INVISIBLE (-4575 4625);
FORCEPROP 1 LAST PATH I84
J 0
(-4500 4625);
DISPLAY 0.872340 (-4500 4625);
PAINT AQUA (-4500 4625);
DISPLAY INVISIBLE (-4500 4625);
FORCEADD Q_RES..2
(-4425 4675);
FORCEPROP 1 LAST PART_NUMBER CS21002FB06
J 0
(-4400 4550);
DISPLAY 0.617021 (-4400 4550);
PAINT BLUE (-4400 4550);
DISPLAY INVISIBLE (-4400 4550);
FORCEPROP 1 LAST WATTAGE 1/16W
J 0
(-4400 4650);
DISPLAY 0.617021 (-4400 4650);
PAINT SKYBLUE (-4400 4650);
FORCEPROP 1 LAST MATERIAL CHIP
J 0
(-4400 4600);
DISPLAY 0.617021 (-4400 4600);
PAINT SKYBLUE (-4400 4600);
FORCEPROP 1 LAST TOLERANCE 1%
J 0
(-4395 4700);
DISPLAY 0.617021 (-4395 4700);
PAINT SKYBLUE (-4395 4700);
FORCEPROP 1 LAST PACK_TYPE 0402LF
J 0
(-4400 4500);
DISPLAY 0.617021 (-4400 4500);
PAINT SKYBLUE (-4400 4500);
FORCEPROP 1 LAST VALUE 1K
J 0
(-4395 4750);
DISPLAY 0.617021 (-4395 4750);
PAINT SKYBLUE (-4395 4750);
FORCEPROP 1 LAST LOCATION R2404
J 0
(-4395 4800);
DISPLAY 0.617021 (-4395 4800);
PAINT AQUA (-4395 4800);
FORCEPROP 1 LASTPIN (-4425 4775) $PN 1
J 0
(-4420 4737);
DISPLAY 0.617021 (-4420 4737);
PAINT MONO (-4420 4737);
FORCEPROP 1 LASTPIN (-4425 4575) $PN 2
J 0
(-4420 4585);
DISPLAY 0.617021 (-4420 4585);
PAINT MONO (-4420 4585);
FORCEPROP 2 LAST CDS_LIB pure_quanta
J 0
(-4425 4675);
DISPLAY INVISIBLE (-4425 4675);
FORCEPROP 1 LAST PATH I85
J 0
(-4375 4850);
DISPLAY 0.978723 (-4375 4850);
PAINT WHITE (-4375 4850);
DISPLAY INVISIBLE (-4375 4850);
FORCEPROP 1 LAST LOCATION R2404
J 0
(-4375 4850);
DISPLAY 1.021277 (-4375 4850);
PAINT AQUA (-4375 4850);
DISPLAY INVISIBLE (-4375 4850);
FORCEPROP 0 LAST $SEC 1
J 0
(-4375 4850);
DISPLAY 0.680851 (-4375 4850);
PAINT MONO (-4375 4850);
DISPLAY INVISIBLE (-4375 4850);
FORCEPROP 0 LAST CDS_SEC 1
J 0
(-4375 4850);
DISPLAY 1.021277 (-4375 4850);
DISPLAY INVISIBLE (-4375 4850);
FORCEADD VCC15..1
(-4425 4900);
FORCEPROP 3 LASTPIN (-4425 4850) SIG_NAME P3V3_AUX\g
J 0
(-4415 4860);
DISPLAY 0.659574 (-4415 4860);
PAINT MONO (-4415 4860);
DISPLAY INVISIBLE (-4415 4860);
FORCEPROP 1 LAST HDL_POWER P3V3_AUX
J 1
(-4425 4950);
DISPLAY 0.617021 (-4425 4950);
PAINT GREEN (-4425 4950);
FORCEPROP 2 LAST CDS_LIB logical_power
J 0
(-4425 4900);
DISPLAY INVISIBLE (-4425 4900);
FORCEPROP 1 LAST PATH I86
J 0
(-4375 4925);
DISPLAY 0.872340 (-4375 4925);
PAINT AQUA (-4375 4925);
DISPLAY INVISIBLE (-4375 4925);
FORCEADD UNIVERSAL_GND..1
(-4575 5075);
FORCEPROP 3 LASTPIN (-4575 5125) SIG_NAME GND\g
J 0
(-4565 5135);
DISPLAY 0.659574 (-4565 5135);
PAINT MONO (-4565 5135);
DISPLAY INVISIBLE (-4565 5135);
FORCEPROP 1 LAST HDL_POWER GND
J 1
(-4550 5000);
DISPLAY 0.872340 (-4550 5000);
PAINT GREEN (-4550 5000);
DISPLAY INVISIBLE (-4550 5000);
FORCEPROP 2 LAST CDS_LIB logical_power
J 0
(-4575 5075);
DISPLAY INVISIBLE (-4575 5075);
FORCEPROP 1 LAST PATH I87
J 0
(-4500 5075);
DISPLAY 0.872340 (-4500 5075);
PAINT AQUA (-4500 5075);
DISPLAY INVISIBLE (-4500 5075);
FORCEADD OFFPAGE..4
(-3475 4300);
FORCEPROP 2 LAST $XR0 251 
J 0
(-3289 4300);
DISPLAY 0.638298 (-3289 4300);
PAINT MONO (-3289 4300);
FORCEPROP 1 LAST COMMENT_BODY TRUE
J 0
(-3500 4200);
DISPLAY 0.872340 (-3500 4200);
PAINT GREEN (-3500 4200);
DISPLAY INVISIBLE (-3500 4200);
FORCEPROP 1 LAST OFFPAGE TRUE
J 0
(-3150 4175);
DISPLAY 0.872340 (-3150 4175);
PAINT GREEN (-3150 4175);
DISPLAY INVISIBLE (-3150 4175);
FORCEPROP 2 LAST CDS_LIB standard
J 0
(-3475 4300);
PAINT MONO (-3475 4300);
DISPLAY INVISIBLE (-3475 4300);
FORCEPROP 2 LAST PATH I88
J 0
(-3275 4350);
DISPLAY 1.021277 (-3275 4350);
DISPLAY INVISIBLE (-3275 4350);
FORCEADD OFFPAGE..2
(-3475 4450);
FORCEPROP 2 LAST $XR0 215 
J 0
(-3286 4450);
DISPLAY 0.638298 (-3286 4450);
PAINT MONO (-3286 4450);
FORCEPROP 1 LAST COMMENT_BODY TRUE
J 0
(-3520 4355);
DISPLAY 0.872340 (-3520 4355);
PAINT GREEN (-3520 4355);
DISPLAY INVISIBLE (-3520 4355);
FORCEPROP 1 LAST OFFPAGE TRUE
J 0
(-3150 4325);
DISPLAY 0.872340 (-3150 4325);
PAINT GREEN (-3150 4325);
DISPLAY INVISIBLE (-3150 4325);
FORCEPROP 2 LAST CDS_LIB standard
J 0
(-3475 4450);
DISPLAY INVISIBLE (-3475 4450);
FORCEPROP 2 LAST PATH I89
J 0
(-3275 4500);
DISPLAY 1.021277 (-3275 4500);
DISPLAY INVISIBLE (-3275 4500);
FORCEADD Q_CAP..1
(-9225 3175);
FORCEPROP 1 LAST PART_NUMBER CH4104K1B00
J 0
(-9175 3000);
DISPLAY 0.617021 (-9175 3000);
PAINT BLUE (-9175 3000);
DISPLAY INVISIBLE (-9175 3000);
FORCEPROP 1 LAST PACK_TYPE 0402
J 0
(-9175 3050);
DISPLAY 0.617021 (-9175 3050);
PAINT SKYBLUE (-9175 3050);
FORCEPROP 1 LAST VOLTAGE 25V
J 0
(-9175 3200);
DISPLAY 0.617021 (-9175 3200);
PAINT SKYBLUE (-9175 3200);
FORCEPROP 1 LAST VALUE 0.1UF
J 0
(-9175 3250);
DISPLAY 0.617021 (-9175 3250);
PAINT SKYBLUE (-9175 3250);
FORCEPROP 1 LAST MATERIAL X7R
J 0
(-9175 3100);
DISPLAY 0.617021 (-9175 3100);
PAINT SKYBLUE (-9175 3100);
FORCEPROP 1 LAST TOLERANCE 10%
J 0
(-9175 3150);
DISPLAY 0.617021 (-9175 3150);
PAINT SKYBLUE (-9175 3150);
FORCEPROP 1 LAST LOCATION PC624
J 0
(-9175 3300);
DISPLAY 0.617021 (-9175 3300);
PAINT AQUA (-9175 3300);
FORCEPROP 1 LASTPIN (-9225 3275) $PN 1
J 0
(-9215 3255);
DISPLAY 0.617021 (-9215 3255);
PAINT MONO (-9215 3255);
FORCEPROP 1 LASTPIN (-9225 3075) $PN 2
J 0
(-9215 3055);
DISPLAY 0.617021 (-9215 3055);
PAINT MONO (-9215 3055);
FORCEPROP 2 LAST CDS_LIB pure_quanta
J 0
(-9225 3175);
DISPLAY INVISIBLE (-9225 3175);
FORCEPROP 1 LAST PATH I9
J 0
(-9175 3325);
DISPLAY 0.978723 (-9175 3325);
PAINT WHITE (-9175 3325);
DISPLAY INVISIBLE (-9175 3325);
FORCEPROP 1 LAST LOCATION PC624
J 0
(-9175 3350);
DISPLAY 1.021277 (-9175 3350);
PAINT AQUA (-9175 3350);
DISPLAY INVISIBLE (-9175 3350);
FORCEPROP 0 LAST $SEC 1
J 0
(-9175 3350);
DISPLAY 0.680851 (-9175 3350);
PAINT MONO (-9175 3350);
DISPLAY INVISIBLE (-9175 3350);
FORCEPROP 0 LAST CDS_SEC 1
J 0
(-9175 3350);
DISPLAY 1.021277 (-9175 3350);
DISPLAY INVISIBLE (-9175 3350);
FORCEADD UNIVERSAL_GND..1
(-4575 5525);
FORCEPROP 3 LASTPIN (-4575 5575) SIG_NAME GND\g
J 0
(-4565 5585);
DISPLAY 0.659574 (-4565 5585);
PAINT MONO (-4565 5585);
DISPLAY INVISIBLE (-4565 5585);
FORCEPROP 1 LAST HDL_POWER GND
J 1
(-4550 5450);
DISPLAY 0.872340 (-4550 5450);
PAINT GREEN (-4550 5450);
DISPLAY INVISIBLE (-4550 5450);
FORCEPROP 2 LAST CDS_LIB logical_power
J 0
(-4575 5525);
DISPLAY INVISIBLE (-4575 5525);
FORCEPROP 1 LAST PATH I90
J 0
(-4500 5525);
DISPLAY 0.872340 (-4500 5525);
PAINT AQUA (-4500 5525);
DISPLAY INVISIBLE (-4500 5525);
FORCEADD UNIVERSAL_GND..1
(-4575 5975);
FORCEPROP 3 LASTPIN (-4575 6025) SIG_NAME GND\g
J 0
(-4565 6035);
DISPLAY 0.659574 (-4565 6035);
PAINT MONO (-4565 6035);
DISPLAY INVISIBLE (-4565 6035);
FORCEPROP 1 LAST HDL_POWER GND
J 1
(-4550 5900);
DISPLAY 0.872340 (-4550 5900);
PAINT GREEN (-4550 5900);
DISPLAY INVISIBLE (-4550 5900);
FORCEPROP 2 LAST CDS_LIB logical_power
J 0
(-4575 5975);
DISPLAY INVISIBLE (-4575 5975);
FORCEPROP 1 LAST PATH I91
J 0
(-4500 5975);
DISPLAY 0.872340 (-4500 5975);
PAINT AQUA (-4500 5975);
DISPLAY INVISIBLE (-4500 5975);
FORCEADD UNIVERSAL_GND..1
(-4575 6425);
FORCEPROP 3 LASTPIN (-4575 6475) SIG_NAME GND\g
J 0
(-4565 6485);
DISPLAY 0.659574 (-4565 6485);
PAINT MONO (-4565 6485);
DISPLAY INVISIBLE (-4565 6485);
FORCEPROP 1 LAST HDL_POWER GND
J 1
(-4550 6350);
DISPLAY 0.872340 (-4550 6350);
PAINT GREEN (-4550 6350);
DISPLAY INVISIBLE (-4550 6350);
FORCEPROP 2 LAST CDS_LIB logical_power
J 0
(-4575 6425);
DISPLAY INVISIBLE (-4575 6425);
FORCEPROP 1 LAST PATH I92
J 0
(-4500 6425);
DISPLAY 0.872340 (-4500 6425);
PAINT AQUA (-4500 6425);
DISPLAY INVISIBLE (-4500 6425);
FORCEADD UNIVERSAL_GND..1
(-4575 6875);
FORCEPROP 3 LASTPIN (-4575 6925) SIG_NAME GND\g
J 0
(-4565 6935);
DISPLAY 0.659574 (-4565 6935);
PAINT MONO (-4565 6935);
DISPLAY INVISIBLE (-4565 6935);
FORCEPROP 1 LAST HDL_POWER GND
J 1
(-4550 6800);
DISPLAY 0.872340 (-4550 6800);
PAINT GREEN (-4550 6800);
DISPLAY INVISIBLE (-4550 6800);
FORCEPROP 2 LAST CDS_LIB logical_power
J 0
(-4575 6875);
DISPLAY INVISIBLE (-4575 6875);
FORCEPROP 1 LAST PATH I93
J 0
(-4500 6875);
DISPLAY 0.872340 (-4500 6875);
PAINT AQUA (-4500 6875);
DISPLAY INVISIBLE (-4500 6875);
FORCEADD UNIVERSAL_GND..1
(-4575 7325);
FORCEPROP 3 LASTPIN (-4575 7375) SIG_NAME GND\g
J 0
(-4565 7385);
DISPLAY 0.659574 (-4565 7385);
PAINT MONO (-4565 7385);
DISPLAY INVISIBLE (-4565 7385);
FORCEPROP 1 LAST HDL_POWER GND
J 1
(-4550 7250);
DISPLAY 0.872340 (-4550 7250);
PAINT GREEN (-4550 7250);
DISPLAY INVISIBLE (-4550 7250);
FORCEPROP 2 LAST CDS_LIB logical_power
J 0
(-4575 7325);
DISPLAY INVISIBLE (-4575 7325);
FORCEPROP 1 LAST PATH I94
J 0
(-4500 7325);
DISPLAY 0.872340 (-4500 7325);
PAINT AQUA (-4500 7325);
DISPLAY INVISIBLE (-4500 7325);
FORCEADD Q_RES..1
(-10725 3725);
FORCEPROP 1 LAST PART_NUMBER CS23572FB05
J 0
(-11200 3775);
DISPLAY 0.638298 (-11200 3775);
DISPLAY INVISIBLE (-11200 3775);
FORCEPROP 1 LAST VALUE 3.57K
J 2
(-10475 3725);
DISPLAY 0.510638 (-10475 3725);
FORCEPROP 1 LAST TOLERANCE 1%
J 0
(-10475 3725);
DISPLAY 0.510638 (-10475 3725);
FORCEPROP 1 LAST PACK_TYPE 0402LF
J 0
(-10475 3575);
DISPLAY 0.510638 (-10475 3575);
FORCEPROP 1 LAST MATERIAL CHIP
J 0
(-10425 3725);
DISPLAY 0.510638 (-10425 3725);
FORCEPROP 1 LAST WATTAGE 1/16W
J 2
(-10200 3725);
DISPLAY 0.510638 (-10200 3725);
FORCEPROP 1 LAST LOCATION PR358
J 0
(-10975 3725);
DISPLAY 0.638298 (-10975 3725);
FORCEPROP 1 LASTPIN (-10825 3725) $PN 1
J 0
(-10813 3737);
DISPLAY 0.787234 (-10813 3737);
PAINT MONO (-10813 3737);
FORCEPROP 1 LASTPIN (-10625 3725) $PN 2
J 0
(-10663 3737);
DISPLAY 0.787234 (-10663 3737);
PAINT MONO (-10663 3737);
FORCEPROP 2 LAST CDS_LIB pure_quanta
J 0
(-10725 3725);
DISPLAY INVISIBLE (-10725 3725);
FORCEPROP 1 LAST PATH I95
J 0
(-10775 3875);
DISPLAY 0.978723 (-10775 3875);
PAINT WHITE (-10775 3875);
DISPLAY INVISIBLE (-10775 3875);
FORCEPROP 0 LAST $SEC 1
J 0
(-11200 3825);
DISPLAY 0.680851 (-11200 3825);
PAINT MONO (-11200 3825);
DISPLAY INVISIBLE (-11200 3825);
FORCEPROP 0 LAST CDS_SEC 1
J 0
(-11200 3825);
DISPLAY 1.021277 (-11200 3825);
DISPLAY INVISIBLE (-11200 3825);
FORCEADD Q_CAP..1
(-6575 8750);
FORCEPROP 1 LAST PART_NUMBER CH4104K1B00
J 0
(-6525 8675);
DISPLAY 0.638298 (-6525 8675);
DISPLAY INVISIBLE (-6525 8675);
FORCEPROP 1 LAST VALUE 0.1UF
J 0
(-6525 8825);
DISPLAY 0.638298 (-6525 8825);
FORCEPROP 1 LAST VOLTAGE 25V
J 0
(-6525 8775);
DISPLAY 0.638298 (-6525 8775);
FORCEPROP 1 LAST TOLERANCE 10%
J 0
(-6525 8725);
DISPLAY 0.638298 (-6525 8725);
FORCEPROP 1 LAST MATERIAL EMPTY
J 0
(-6525 8700);
DISPLAY 0.638298 (-6525 8700);
PAINT RED (-6525 8700);
FORCEPROP 1 LAST PACK_TYPE 0402
J 0
(-6525 8625);
DISPLAY 0.638298 (-6525 8625);
FORCEPROP 1 LAST LOCATION PC2365
J 0
(-6525 8850);
DISPLAY 0.978723 (-6525 8850);
FORCEPROP 1 LASTPIN (-6575 8850) $PN 1
J 0
(-6565 8830);
DISPLAY 0.787234 (-6565 8830);
PAINT MONO (-6565 8830);
FORCEPROP 1 LASTPIN (-6575 8650) $PN 2
J 0
(-6565 8630);
DISPLAY 0.787234 (-6565 8630);
PAINT MONO (-6565 8630);
FORCEPROP 2 LAST CDS_LIB pure_quanta
J 0
(-6575 8750);
DISPLAY INVISIBLE (-6575 8750);
FORCEPROP 1 LAST PATH I96
J 0
(-6525 8900);
DISPLAY 0.978723 (-6525 8900);
PAINT WHITE (-6525 8900);
DISPLAY INVISIBLE (-6525 8900);
FORCEPROP 0 LAST $SEC 1
J 0
(-6525 8900);
DISPLAY 0.680851 (-6525 8900);
PAINT MONO (-6525 8900);
DISPLAY INVISIBLE (-6525 8900);
FORCEPROP 0 LAST CDS_SEC 1
J 0
(-6525 8900);
DISPLAY 1.021277 (-6525 8900);
DISPLAY INVISIBLE (-6525 8900);
FORCEADD QUANTA_TITLE_BLOCK_C..1
(-3000 2775);
FORCEPROP 0 LAST CDS_CON_LAST_MODIFIED Fri Aug 25 14:04:48 2023
J 0
(-4885 2790);
DISPLAY INVISIBLE (-4885 2790);
FORCEPROP 1 LAST CUSTOM_TXT_CDS <CON_LAST_MODIFIED>
J 0
(-4885 2790);
DISPLAY 0.978723 (-4885 2790);
FORCEPROP 2 LAST CUSTOM_TXT_CDS <XR_PAGE_TITLE>
J 0
(-10890 8025);
DISPLAY 0.638298 (-10890 8025);
PAINT PINK (-10890 8025);
DISPLAY INVISIBLE (-10890 8025);
FORCEPROP 1 LAST CUSTOM_TXT_CDS <NAME_2>
J 0
(-6175 2825);
FORCEPROP 1 LAST CUSTOM_TXT_CDS <NAME_1>
J 0
(-6175 2950);
FORCEPROP 1 LAST CUSTOM_TXT_CDS <Q_NUMBER>
J 0
(-4403 2878);
DISPLAY 1.212766 (-4403 2878);
FORCEPROP 1 LAST CUSTOM_TXT_CDS <Q_PROJ>
J 0
(-5382 2877);
DISPLAY 1.212766 (-5382 2877);
FORCEPROP 1 LAST CUSTOM_TXT_CDS <Q_REV>
J 0
(-3184 2878);
DISPLAY 1.212766 (-3184 2878);
FORCEPROP 1 LAST CUSTOM_TXT_CDS <CON_PAGE_NUM> OF <CON_TOTAL_PAGES>
J 0
(-3446 2793);
DISPLAY 0.978723 (-3446 2793);
FORCEPROP 1 LAST Q_TITLE VCCD_HV CPU0 VR CONTROLLER (1/2)
J 0
(-12300 2825);
DISPLAY 2.446809 (-12300 2825);
PAINT GREEN (-12300 2825);
FORCEPROP 1 LAST Q_DEPT 
J 1
(-6763 2824);
DISPLAY 1.957447 (-6763 2824);
PAINT GREEN (-6763 2824);
FORCEPROP 2 LAST CDS_XR_PAGE_TITLE CR-278 : @S9S_MB_2U_LIB.S9S_MB_2U(SCH_1):PAGE278
J 0
(-10890 8025);
DISPLAY 0.638298 (-10890 8025);
PAINT PINK (-10890 8025);
DISPLAY INVISIBLE (-10890 8025);
FORCEPROP 1 LAST CDS_LMAN_SYM_OUTLINE -9475,6775,100,-125
J 0
(-3000 2775);
DISPLAY 0.468085 (-3000 2775);
PAINT GREEN (-3000 2775);
DISPLAY INVISIBLE (-3000 2775);
FORCEPROP 2 LAST CDS_LIB pure_quanta
J 0
(-3000 2775);
DISPLAY INVISIBLE (-3000 2775);
FORCEPROP 2 LAST PAGE_BORDER TRUE
J 0
(-10890 8025);
DISPLAY 0.638298 (-10890 8025);
PAINT PINK (-10890 8025);
DISPLAY INVISIBLE (-10890 8025);
FORCEPROP 1 LAST COMMENT_BODY TRUE
J 0
(-2988 2762);
DISPLAY 0.978723 (-2988 2762);
PAINT GREEN (-2988 2762);
DISPLAY INVISIBLE (-2988 2762);
FORCEADD DNS..1
(-6550 8750);
PAINT RED (-6550 8750);
FORCEPROP 1 LAST COMMENT_BODY TRUE
R 1
J 0
(-6475 8525);
DISPLAY 0.872340 (-6475 8525);
PAINT GREEN (-6475 8525);
DISPLAY INVISIBLE (-6475 8525);
FORCEPROP 2 LAST CDS_LIB mstr_misc
J 0
(-6550 8750);
DISPLAY INVISIBLE (-6550 8750);
FORCEADD DNS..2
(-10700 3850);
PAINT RED (-10700 3850);
FORCEPROP 1 LAST COMMENT_BODY TRUE
R 1
J 0
(-10625 3625);
DISPLAY 0.872340 (-10625 3625);
PAINT GREEN (-10625 3625);
DISPLAY INVISIBLE (-10625 3625);
FORCEPROP 2 LAST CDS_LIB mstr_misc
J 0
(-10700 3850);
PAINT MONO (-10700 3850);
DISPLAY INVISIBLE (-10700 3850);
FORCEADD DNS..1
(-9350 3150);
PAINT RED (-9350 3150);
FORCEPROP 1 LAST COMMENT_BODY TRUE
R 1
J 0
(-9275 2925);
DISPLAY 0.872340 (-9275 2925);
PAINT GREEN (-9275 2925);
DISPLAY INVISIBLE (-9275 2925);
FORCEPROP 2 LAST CDS_LIB mstr_misc
J 0
(-9350 3150);
DISPLAY INVISIBLE (-9350 3150);
FORCEADD DNS..1
(-8975 9125);
PAINT RED (-8975 9125);
FORCEPROP 1 LAST COMMENT_BODY TRUE
R 1
J 0
(-8900 8900);
DISPLAY 0.872340 (-8900 8900);
PAINT GREEN (-8900 8900);
DISPLAY INVISIBLE (-8900 8900);
FORCEPROP 2 LAST CDS_LIB mstr_misc
J 0
(-8975 9125);
DISPLAY INVISIBLE (-8975 9125);
FORCEADD DNS..1
(-8600 3150);
PAINT RED (-8600 3150);
FORCEPROP 1 LAST COMMENT_BODY TRUE
R 1
J 0
(-8525 2925);
DISPLAY 0.872340 (-8525 2925);
PAINT GREEN (-8525 2925);
DISPLAY INVISIBLE (-8525 2925);
FORCEPROP 2 LAST CDS_LIB mstr_misc
J 0
(-8600 3150);
DISPLAY INVISIBLE (-8600 3150);
FORCEADD DNS..1
(-5075 3550);
PAINT RED (-5075 3550);
FORCEPROP 1 LAST COMMENT_BODY TRUE
R 1
J 0
(-5000 3325);
DISPLAY 0.872340 (-5000 3325);
PAINT GREEN (-5000 3325);
DISPLAY INVISIBLE (-5000 3325);
FORCEPROP 2 LAST CDS_LIB mstr_misc
J 0
(-5075 3550);
DISPLAY INVISIBLE (-5075 3550);
FORCEADD DNS..1
(-4850 4300);
PAINT RED (-4850 4300);
FORCEPROP 1 LAST COMMENT_BODY TRUE
R 1
J 0
(-4775 4075);
DISPLAY 0.872340 (-4775 4075);
PAINT GREEN (-4775 4075);
DISPLAY INVISIBLE (-4775 4075);
FORCEPROP 2 LAST CDS_LIB mstr_misc
J 0
(-4850 4300);
DISPLAY INVISIBLE (-4850 4300);
FORCEADD DNS..1
(-6200 8750);
PAINT RED (-6200 8750);
FORCEPROP 1 LAST COMMENT_BODY TRUE
R 1
J 0
(-6125 8525);
DISPLAY 0.872340 (-6125 8525);
PAINT GREEN (-6125 8525);
DISPLAY INVISIBLE (-6125 8525);
FORCEPROP 2 LAST CDS_LIB mstr_misc
J 0
(-6200 8750);
DISPLAY INVISIBLE (-6200 8750);
WIRE 16 -1 (-9975 7200)(-9975 7100);
WIRE 16 -1 (-5025 9025)(-5025 8950);
WIRE 16 -1 (-12100 8850)(-12100 8900);
WIRE 16 -1 (-11875 8850)(-12100 8850);
WIRE 16 -1 (-12100 8775)(-12100 8850);
WIRE 16 -1 (-9600 5550)(-9600 5500);
WIRE 16 -1 (-10275 9100)(-10275 9150);
WIRE 16 -1 (-10275 9100)(-9950 9100);
WIRE 16 -1 (-4425 4850)(-4425 4775);
WIRE 16 -1 (-11350 3725)(-11350 3700);
WIRE 16 -1 (-11350 3725)(-10825 3725);
WIRE 16 -1 (-9225 2925)(-9225 2975);
WIRE 16 -1 (-12100 8450)(-12100 8375);
WIRE 16 -1 (-11875 8450)(-12100 8450);
WIRE 16 -1 (-12100 8575)(-12100 8450);
WIRE 16 -1 (-10000 6425)(-10000 6375);
WIRE 16 -1 (-10000 6425)(-10425 6425);
WIRE 16 -1 (-8475 2975)(-8475 2925);
WIRE 16 -1 (-8600 2975)(-8475 2975);
WIRE 16 -1 (-8475 3075)(-8475 2975);
WIRE 16 -1 (-8250 3325)(-8250 3400);
WIRE 16 -1 (-8300 4550)(-8300 4475);
WIRE 16 -1 (-8300 4550)(-8150 4550);
WIRE 16 -1 (-5850 3375)(-5850 3450);
WIRE 16 -1 (-5150 3350)(-5150 3450);
WIRE 16 -1 (-8350 5400)(-8350 5550);
WIRE 16 -1 (-8900 9100)(-8350 9100);
WIRE 16 -1 (-5425 8075)(-5825 8075);
WIRE 16 -1 (-5425 8550)(-5825 8550);
WIRE 16 -1 (-4100 4050)(-4100 3975);
WIRE 16 -1 (-4875 4050)(-4100 4050);
WIRE 16 -1 (-4575 4700)(-4575 4675);
WIRE 16 -1 (-5100 4700)(-4575 4700);
WIRE 16 -1 (-4575 5150)(-4575 5125);
WIRE 16 -1 (-5100 5150)(-4575 5150);
WIRE 16 -1 (-4575 5600)(-4575 5575);
WIRE 16 -1 (-5100 5600)(-4575 5600);
WIRE 16 -1 (-4575 6050)(-4575 6025);
WIRE 16 -1 (-5100 6050)(-4575 6050);
WIRE 16 -1 (-4575 6500)(-4575 6475);
WIRE 16 -1 (-5100 6500)(-4575 6500);
WIRE 16 -1 (-4575 6950)(-4575 6925);
WIRE 16 -1 (-5100 6950)(-4575 6950);
WIRE 16 -1 (-4575 7400)(-4575 7375);
WIRE 16 -1 (-5100 7400)(-4575 7400);
WIRE 17 273 (-4650 7900)(-3079 7900);
WIRE 17 273 (-3079 9375)(-3079 7900);
WIRE 17 273 (-4650 9375)(-4650 7900);
WIRE 17 273 (-4650 9375)(-3079 9375);
WIRE 16 -1 (-10800 6425)(-10625 6425);
WIRE 16 -1 (-11675 6575)(-10800 6575);
FORCEPROP 2 LAST SIG_NAME VSENSE_PVCCD_HV_CPU0_DN
J 0
(-11585 6585);
DISPLAY 0.617021 (-11585 6585);
WIRE 16 -1 (-10800 6425)(-10800 6575);
WIRE 16 -1 (-10800 6575)(-9000 6575);
WIRE 16 -1 (-9000 6675)(-9000 6575);
WIRE 16 -1 (-8350 6575)(-9000 6575);
WIRE 16 -1 (-8350 6575)(-8350 6650);
WIRE 16 -1 (-8150 6650)(-8350 6650);
WIRE 16 -1 (-8150 7800)(-9750 7800);
FORCEPROP 2 LAST SIG_NAME SMB_CLK_PVCCD_HV_CPU0
J 0
(-9185 7810);
DISPLAY 0.617021 (-9185 7810);
WIRE 16 -1 (-9750 8350)(-8150 8350);
FORCEPROP 2 LAST SIG_NAME SVID_DIO_PVCCD_HV_CPU0_R
J 0
(-9185 8360);
DISPLAY 0.617021 (-9185 8360);
WIRE 16 -1 (-8150 8200)(-9750 8200);
FORCEPROP 2 LAST SIG_NAME SVID_ALERT_PVCCD_HV_CPU0_R
J 0
(-9185 8210);
DISPLAY 0.617021 (-9185 8210);
WIRE 16 -1 (-8150 4150)(-9300 4150);
FORCEPROP 2 LAST SIG_NAME NC_PVCCD_HV_CPU0_BVR_RDY
J 0
(-9235 4160);
DISPLAY 0.617021 (-9235 4160);
WIRE 16 -1 (-8150 8500)(-9750 8500);
FORCEPROP 2 LAST SIG_NAME SVID_CLK_PVCCD_HV_CPU0_R
J 0
(-9185 8510);
DISPLAY 0.617021 (-9185 8510);
WIRE 16 -1 (-9750 7500)(-8150 7500);
FORCEPROP 2 LAST SIG_NAME NC_PVCCD_HV_CPU0_SMB_ALERT
J 0
(-9335 7510);
DISPLAY 0.617021 (-9335 7510);
WIRE 16 -1 (-9750 8800)(-8150 8800);
FORCEPROP 2 LAST SIG_NAME PVCCD_HV_CPU0_EN_R
J 0
(-9185 8810);
DISPLAY 0.617021 (-9185 8810);
WIRE 16 -1 (-8150 7650)(-9750 7650);
FORCEPROP 2 LAST SIG_NAME SMB_DIO_PVCCD_HV_CPU0
J 0
(-9185 7660);
DISPLAY 0.617021 (-9185 7660);
WIRE 16 -1 (-8350 6900)(-8150 6900);
WIRE 16 -1 (-8350 6950)(-8350 6900);
WIRE 16 -1 (-9000 6875)(-9000 6950);
WIRE 16 -1 (-8350 6950)(-9000 6950);
FORCEPROP 2 LAST SIG_NAME SH_PVCCD_HV_CPU0_R
J 0
(-8985 6960);
DISPLAY 0.617021 (-8985 6960);
WIRE 16 -1 (-9350 6950)(-9000 6950);
WIRE 16 -1 (-9325 8950)(-9750 8950);
WIRE 16 -1 (-9325 8950)(-8150 8950);
FORCEPROP 2 LAST SIG_NAME PWRGD_PVCCD_HV_CPU0_R
J 0
(-9185 8960);
DISPLAY 0.617021 (-9185 8960);
WIRE 16 -1 (-9325 9100)(-9750 9100);
WIRE 16 -1 (-9325 8950)(-9325 9100);
WIRE 16 -1 (-9100 9100)(-9325 9100);
WIRE 16 -1 (-8475 3550)(-8425 3550);
WIRE 16 -1 (-8425 3550)(-8425 3600);
WIRE 16 -1 (-8150 3600)(-8425 3600);
WIRE 16 -1 (-9225 3275)(-9225 3600);
WIRE 16 -1 (-9225 3600)(-8425 3600);
WIRE 16 -1 (-9675 3600)(-9350 3600);
FORCEPROP 2 LAST SIG_NAME PVCCD_HV_CPU0_ISENSE_P
J 0
(-9435 3610);
DISPLAY 0.617021 (-9435 3610);
WIRE 16 -1 (-9350 3600)(-9225 3600);
WIRE 16 -1 (-9350 3275)(-9350 3600);
WIRE 16 -1 (-8475 3275)(-8475 3500);
WIRE 16 -1 (-8150 3500)(-8475 3500);
WIRE 16 -1 (-8600 3275)(-8600 3500);
WIRE 16 -1 (-8600 3500)(-8475 3500);
WIRE 16 -1 (-9675 3500)(-8725 3500);
FORCEPROP 2 LAST SIG_NAME PVCCD_HV_CPU0_ISENSE_N
J 0
(-9435 3510);
DISPLAY 0.617021 (-9435 3510);
WIRE 16 -1 (-8725 3500)(-8600 3500);
WIRE 16 -1 (-8725 3550)(-8725 3500);
WIRE 16 -1 (-8675 3550)(-8725 3550);
WIRE 16 -1 (-9600 5150)(-9600 4700);
WIRE 16 -1 (-9600 4700)(-8150 4700);
FORCEPROP 2 LAST SIG_NAME PVCCD_HV_CPU0_PIN_ALT
J 0
(-9235 4710);
DISPLAY 0.617021 (-9235 4710);
WIRE 16 -1 (-9700 4700)(-9600 4700);
WIRE 16 -1 (-8150 5800)(-8350 5800);
WIRE 16 -1 (-8350 5550)(-8350 5800);
WIRE 16 -1 (-8350 5550)(-8150 5550);
WIRE 16 -1 (-8150 4950)(-9275 4950);
FORCEPROP 2 LAST SIG_NAME PVCCD_HV_CPU0_FAULT
J 0
(-9235 4960);
DISPLAY 0.617021 (-9235 4960);
WIRE 16 -1 (-9275 5150)(-9275 4950);
WIRE 16 -1 (-8150 3400)(-8250 3400);
WIRE 16 -1 (-10625 3850)(-10225 3850);
WIRE 16 -1 (-10225 3850)(-8150 3850);
FORCEPROP 2 LAST SIG_NAME PVCCD_HV_CPU0_ADDR
J 0
(-9235 3860);
DISPLAY 0.617021 (-9235 3860);
WIRE 16 -1 (-10225 3725)(-10225 3850);
WIRE 16 -1 (-10625 3725)(-10225 3725);
WIRE 16 -1 (-6800 4700)(-5300 4700);
FORCEPROP 2 LAST SIG_NAME NC_PVCCD_HV_CPU0_ACSP8
J 0
(-6635 4710);
DISPLAY 0.617021 (-6635 4710);
WIRE 16 -1 (-6800 4800)(-5575 4800);
FORCEPROP 2 LAST SIG_NAME NC_PVCCD_HV_CPU0_APWM8
J 0
(-6635 4810);
DISPLAY 0.617021 (-6635 4810);
WIRE 16 -1 (-5150 3650)(-5150 3750);
WIRE 16 -1 (-4025 3750)(-5150 3750);
FORCEPROP 2 LAST SIG_NAME PVCCD_HV_CPU0_ATSEN
J 0
(-4885 3760);
DISPLAY 0.617021 (-4885 3760);
WIRE 16 -1 (-5850 3750)(-5850 3650);
WIRE 16 -1 (-5150 3750)(-5850 3750);
WIRE 16 -1 (-6800 3750)(-5850 3750);
WIRE 16 -1 (-6800 5600)(-5300 5600);
FORCEPROP 2 LAST SIG_NAME NC_PVCCD_HV_CPU0_ACSP6
J 0
(-6635 5610);
DISPLAY 0.617021 (-6635 5610);
WIRE 16 -1 (-6800 5700)(-5575 5700);
FORCEPROP 2 LAST SIG_NAME NC_PVCCD_HV_CPU0_APWM6
J 0
(-6635 5710);
DISPLAY 0.617021 (-6635 5710);
WIRE 16 -1 (-6800 6050)(-5300 6050);
FORCEPROP 2 LAST SIG_NAME NC_PVCCD_HV_CPU0_ACSP5
J 0
(-6635 6060);
DISPLAY 0.617021 (-6635 6060);
WIRE 16 -1 (-6800 6150)(-5575 6150);
FORCEPROP 2 LAST SIG_NAME NC_PVCCD_HV_CPU0_APWM5
J 0
(-6635 6160);
DISPLAY 0.617021 (-6635 6160);
WIRE 16 -1 (-6800 7950)(-5575 7950);
FORCEPROP 2 LAST SIG_NAME PVCCD_HV_CPU0_APWM1
J 0
(-6635 7960);
DISPLAY 0.617021 (-6635 7960);
WIRE 16 -1 (-6800 5150)(-5300 5150);
FORCEPROP 2 LAST SIG_NAME NC_PVCCD_HV_CPU0_ACSP7
J 0
(-6635 5160);
DISPLAY 0.617021 (-6635 5160);
WIRE 16 -1 (-6800 4050)(-5375 4050);
FORCEPROP 2 LAST SIG_NAME PVCCD_HV_CPU0_ISYS_R
J 0
(-6485 4060);
DISPLAY 0.617021 (-6485 4060);
WIRE 16 -1 (-5375 4050)(-5075 4050);
WIRE 16 -1 (-5375 4050)(-5375 4300);
WIRE 16 -1 (-4975 4300)(-5375 4300);
WIRE 16 -1 (-5825 8375)(-5825 8475);
WIRE 16 -1 (-5425 8475)(-5825 8475);
WIRE 16 -1 (-6225 8375)(-6225 8475);
WIRE 16 -1 (-5825 8475)(-6225 8475);
WIRE 16 -1 (-6225 8475)(-6650 8475);
FORCEPROP 2 LAST SIG_NAME PVCCD_HV_CPU0_VREF
J 0
(-6610 8485);
DISPLAY 0.617021 (-6610 8485);
WIRE 16 -1 (-6650 8650)(-6650 8475);
WIRE 16 -1 (-6800 8650)(-6650 8650);
WIRE 16 -1 (-5575 7500)(-6800 7500);
FORCEPROP 2 LAST SIG_NAME NC_PVCCD_HV_CPU0_APWM2
J 0
(-6635 7510);
DISPLAY 0.617021 (-6635 7510);
WIRE 16 -1 (-6800 5250)(-5575 5250);
FORCEPROP 2 LAST SIG_NAME NC_PVCCD_HV_CPU0_APWM7
J 0
(-6635 5260);
DISPLAY 0.617021 (-6635 5260);
WIRE 16 -1 (-5575 7050)(-6800 7050);
FORCEPROP 2 LAST SIG_NAME NC_PVCCD_HV_CPU0_APWM3
J 0
(-6635 7060);
DISPLAY 0.617021 (-6635 7060);
WIRE 16 -1 (-5575 6600)(-6800 6600);
FORCEPROP 2 LAST SIG_NAME NC_PVCCD_HV_CPU0_APWM4
J 0
(-6635 6610);
DISPLAY 0.617021 (-6635 6610);
WIRE 16 -1 (-6800 6500)(-5300 6500);
FORCEPROP 2 LAST SIG_NAME NC_PVCCD_HV_CPU0_ACSP4
J 0
(-6635 6510);
DISPLAY 0.617021 (-6635 6510);
WIRE 16 -1 (-6800 6950)(-5300 6950);
FORCEPROP 2 LAST SIG_NAME NC_PVCCD_HV_CPU0_ACSP3
J 0
(-6635 6960);
DISPLAY 0.617021 (-6635 6960);
WIRE 16 -1 (-5425 4450)(-6800 4450);
FORCEPROP 2 LAST SIG_NAME IRQ_PVCCD_CPU0_VRHOT_LVC3_R_N
J 0
(-6635 4460);
DISPLAY 0.638298 (-6635 4460);
WIRE 16 -1 (-6800 7400)(-5300 7400);
FORCEPROP 2 LAST SIG_NAME NC_PVCCD_HV_CPU0_ACSP2
J 0
(-6635 7410);
DISPLAY 0.617021 (-6635 7410);
WIRE 16 -1 (-6800 8950)(-6575 8950);
FORCEPROP 2 LAST SIG_NAME PVCCD_HV_CPU0_VCC
J 0
(-6610 8960);
DISPLAY 0.617021 (-6610 8960);
WIRE 16 -1 (-6575 8850)(-6575 8950);
WIRE 16 -1 (-6575 8950)(-6225 8950);
WIRE 16 -1 (-6225 8850)(-6225 8950);
WIRE 16 -1 (-6225 8950)(-5825 8950);
WIRE 16 -1 (-5600 8950)(-5825 8950);
WIRE 16 -1 (-5825 8850)(-5825 8950);
WIRE 16 -1 (-6800 7850)(-5575 7850);
FORCEPROP 2 LAST SIG_NAME PVCCD_HV_CPU0_ACSP1
J 0
(-6635 7860);
DISPLAY 0.617021 (-6635 7860);
WIRE 16 -1 (-6575 8650)(-6575 8550);
WIRE 16 -1 (-6575 8550)(-6225 8550);
WIRE 16 -1 (-6225 8650)(-6225 8550);
WIRE 16 -1 (-6225 8550)(-5825 8550);
WIRE 16 -1 (-5825 8650)(-5825 8550);
WIRE 16 -1 (-10800 8350)(-10900 8350);
WIRE 16 -1 (-9950 8350)(-10800 8350);
FORCEPROP 2 LAST SIG_NAME SVID_DIO1_CPU0_R
J 0
(-10660 8360);
DISPLAY 0.617021 (-10660 8360);
WIRE 16 -1 (-10800 8575)(-10800 8350);
WIRE 16 -1 (-11250 8575)(-10800 8575);
WIRE 17 273 (-12225 2950)(-10400 2950);
WIRE 17 273 (-10400 3175)(-10400 2950);
WIRE 17 273 (-12225 3175)(-12225 2950);
WIRE 17 273 (-12225 3175)(-10400 3175);
WIRE 16 -1 (-9350 3075)(-9350 2975);
WIRE 16 -1 (-9350 2975)(-9225 2975);
WIRE 16 -1 (-9225 2975)(-9225 3075);
WIRE 17 273 (-11950 7050)(-11625 7050);
WIRE 17 273 (-11625 7050)(-11625 6500);
WIRE 17 273 (-11950 6500)(-11950 7050);
WIRE 17 273 (-11950 6500)(-11625 6500);
WIRE 16 -1 (-10800 7100)(-10575 7100);
WIRE 16 -1 (-10800 6950)(-10800 7100);
WIRE 16 -1 (-10675 6950)(-10800 6950);
WIRE 16 -1 (-11675 6950)(-10800 6950);
FORCEPROP 2 LAST SIG_NAME VSENSE_PVCCD_HV_CPU0_DP
J 0
(-11585 6960);
DISPLAY 0.617021 (-11585 6960);
WIRE 16 -1 (-11875 8850)(-11875 8775);
WIRE 16 -1 (-11625 8850)(-11875 8850);
WIRE 16 -1 (-11625 8675)(-11450 8675);
WIRE 16 -1 (-11625 8850)(-11625 8675);
WIRE 16 -1 (-11625 8675)(-11625 8575);
WIRE 16 -1 (-11625 8575)(-11450 8575);
WIRE 16 -1 (-10725 8675)(-11250 8675);
WIRE 16 -1 (-10900 8500)(-10725 8500);
WIRE 16 -1 (-10725 8500)(-10725 8675);
WIRE 16 -1 (-9950 8500)(-10725 8500);
FORCEPROP 2 LAST SIG_NAME SVID_CLK1_CPU0_R
J 0
(-10660 8510);
DISPLAY 0.617021 (-10660 8510);
WIRE 16 -1 (-10900 8800)(-9950 8800);
FORCEPROP 2 LAST SIG_NAME FM_PVCCD_HV_CPU0_EN
J 0
(-10810 8810);
DISPLAY 0.617021 (-10810 8810);
WIRE 16 -1 (-10900 8200)(-9950 8200);
FORCEPROP 2 LAST SIG_NAME SVID_ALERT1_CPU0_R_N
J 0
(-10785 8210);
DISPLAY 0.617021 (-10785 8210);
WIRE 16 -1 (-10900 8950)(-9950 8950);
FORCEPROP 2 LAST SIG_NAME PWRGD_PVCCD_HV_CPU0
J 0
(-10810 8960);
DISPLAY 0.617021 (-10810 8960);
WIRE 16 -1 (-9975 7100)(-10375 7100);
WIRE 16 -1 (-10425 6950)(-9550 6950);
FORCEPROP 2 LAST SIG_NAME SH_PVCCD_HV_CPU0
J 0
(-10310 6960);
DISPLAY 0.617021 (-10310 6960);
WIRE 16 -1 (-9275 5500)(-9275 5350);
WIRE 16 -1 (-9275 5500)(-9600 5500);
WIRE 16 -1 (-9600 5350)(-9600 5500);
WIRE 16 -1 (-8600 3075)(-8600 2975);
WIRE 16 -1 (-5025 8950)(-5400 8950);
WIRE 16 -1 (-4425 4575)(-4425 4450);
WIRE 16 -1 (-3525 4450)(-4425 4450);
WIRE 16 -1 (-5225 4450)(-4425 4450);
FORCEPROP 2 LAST SIG_NAME IRQ_PVCCD_CPU0_VRHOT_LVC3_N
J 0
(-4310 4460);
DISPLAY 0.617021 (-4310 4460);
WIRE 16 -1 (-4775 4300)(-3525 4300);
FORCEPROP 2 LAST SIG_NAME PVCCD_HV_CPU0_NVDIMM_ISENSE
J 0
(-4310 4310);
DISPLAY 0.617021 (-4310 4310);
WIRE 16 -1 (-9875 3500)(-11100 3500);
FORCEPROP 2 LAST SIG_NAME P12V_AUX_CPU0_DIMM_ISEN_N
J 0
(-10960 3510);
DISPLAY 0.617021 (-10960 3510);
WIRE 16 -1 (-9875 3600)(-11100 3600);
FORCEPROP 2 LAST SIG_NAME P12V_AUX_CPU0_DIMM_ISEN_P
J 0
(-10960 3610);
DISPLAY 0.617021 (-10960 3610);
WIRE 16 -1 (-11775 3850)(-10825 3850);
FORCEPROP 2 LAST SIG_NAME PVCCD_HV_CPU0_VREF
J 0
(-11735 3860);
DISPLAY 0.617021 (-11735 3860);
WIRE 16 -1 (-6225 8175)(-6225 8075);
WIRE 16 -1 (-6225 8075)(-5825 8075);
WIRE 16 -1 (-5825 8075)(-5825 8175);
WIRE 16 -1 (-11875 8575)(-11875 8450);
WIRE 16 -1 (-9950 7650)(-11150 7650);
FORCEPROP 2 LAST SIG_NAME SMB_VR_3V3AUX_SDA_R2
J 0
(-11085 7660);
DISPLAY 0.617021 (-11085 7660);
WIRE 16 -1 (-11150 7800)(-9950 7800);
FORCEPROP 2 LAST SIG_NAME SMB_VR_3V3AUX_SCL_R2
J 0
(-11085 7810);
DISPLAY 0.617021 (-11085 7810);
DOT 1 (-4425 4450);
DOT 1 (-5825 8475);
DOT 1 (-6225 8950);
DOT 1 (-6225 8475);
DOT 1 (-5825 8075);
DOT 1 (-8350 5550);
DOT 1 (-5150 3750);
DOT 1 (-5375 4050);
DOT 1 (-5850 3750);
DOT 1 (-8425 3600);
DOT 1 (-8475 3500);
DOT 1 (-8600 3500);
DOT 1 (-8725 3500);
DOT 1 (-8475 2975);
DOT 1 (-9325 8950);
DOT 1 (-9325 9100);
DOT 1 (-10725 8500);
DOT 1 (-9000 6950);
DOT 1 (-9000 6575);
DOT 1 (-9600 5500);
DOT 1 (-10800 8350);
DOT 1 (-11625 8675);
DOT 1 (-11875 8850);
DOT 1 (-12100 8850);
DOT 1 (-12100 8450);
DOT 1 (-10800 6575);
DOT 1 (-10800 6950);
DOT 1 (-9600 4700);
DOT 1 (-9225 3600);
DOT 1 (-9350 3600);
DOT 1 (-10225 3850);
DOT 1 (-9225 2975);
DOT 1 (-5825 8950);
DOT 1 (-6575 8950);
DOT 1 (-6225 8550);
DOT 1 (-5825 8550);
FORCENOTE
LOAD-LINE=0.80MINI OHM
(-4625 8225) 0;
DISPLAY LEFT (-4625 8225);
DISPLAY 0.936170 (-4625 8225);
PAINT WHITE (-4625 8225);
FORCENOTE
WORK FREQUENCY=700KHZ
(-4625 8150) 0;
DISPLAY LEFT (-4625 8150);
DISPLAY 0.936170 (-4625 8150);
PAINT WHITE (-4625 8150);
FORCENOTE
SLEW RATE=8.6A/US(EMR 8A/US)
(-4625 8300) 0;
DISPLAY LEFT (-4625 8300);
DISPLAY 0.936170 (-4625 8300);
PAINT RED (-4625 8300);
FORCENOTE
(EMR 20A(10A-30A)
(-4650 8375) 0;
DISPLAY LEFT (-4650 8375);
DISPLAY 0.936170 (-4650 8375);
PAINT RED (-4650 8375);
FORCENOTE
CURRENT STEP=17A(8A-25A)
(-4625 8450) 0;
DISPLAY LEFT (-4625 8450);
DISPLAY 0.936170 (-4625 8450);
PAINT RED (-4625 8450);
FORCENOTE
MAX CURRENT=25A(EMR 30A)
(-4625 8600) 0;
DISPLAY LEFT (-4625 8600);
DISPLAY 0.936170 (-4625 8600);
PAINT RED (-4625 8600);
FORCENOTE
TDC=23A(EMR 26A)
(-4625 8675) 0;
DISPLAY LEFT (-4625 8675);
DISPLAY 0.936170 (-4625 8675);
PAINT RED (-4625 8675);
FORCENOTE
(FUTURE 1.189VMX/1.081VMIN)
(-4650 8750) 0;
DISPLAY LEFT (-4650 8750);
DISPLAY 0.936170 (-4650 8750);
PAINT RED (-4650 8750);
FORCENOTE
TOTAL TOLERANCE=1.192MAX/1.086VMIN
(-4625 8825) 0;
DISPLAY LEFT (-4625 8825);
DISPLAY 0.936170 (-4625 8825);
PAINT RED (-4625 8825);
FORCENOTE
PVCCD_HV_CPU0 SPECIFICATION
(-4625 9303) 0;
DISPLAY LEFT (-4625 9303);
DISPLAY 1.021277 (-4625 9303);
PAINT WHITE (-4625 9303);
FORCENOTE
MAX VOLTAGE VIA BIOS COMMAND=1.145V
(-4625 9125) 0;
DISPLAY LEFT (-4625 9125);
DISPLAY 0.936170 (-4625 9125);
PAINT WHITE (-4625 9125);
FORCENOTE
CONFIRM ADDRESS SETTING
(-11275 4050) 0;
DISPLAY LEFT (-11275 4050);
DISPLAY 1.021277 (-11275 4050);
PAINT SKYBLUE (-11275 4050);
FORCENOTE
SET FW CODE FUNCTION TO BVR_EN
(-10125 4550) 0;
DISPLAY LEFT (-10125 4550);
DISPLAY 1.021277 (-10125 4550);
PAINT SKYBLUE (-10125 4550);
FORCENOTE
TRACE SPACING = 5MIL
(-11900 6250) 0;
DISPLAY LEFT (-11900 6250);
DISPLAY 1.021277 (-11900 6250);
PAINT WHITE (-11900 6250);
FORCENOTE
TRACE WIDTH = 10MIL
(-11900 6325) 0;
DISPLAY LEFT (-11900 6325);
DISPLAY 1.021277 (-11900 6325);
PAINT WHITE (-11900 6325);
FORCENOTE
DIFFERENTIAL PAIR
(-11900 6400) 0;
DISPLAY LEFT (-11900 6400);
DISPLAY 1.021277 (-11900 6400);
PAINT WHITE (-11900 6400);
FORCENOTE
I2C(7BIT/8BIT)
(-11096 3100) 0;
DISPLAY LEFT (-11096 3100);
DISPLAY 0.808511 (-11096 3100);
PAINT WHITE (-11096 3100);
FORCENOTE
SVID / I2C ADDRESS
(-12046 3225) 0;
DISPLAY LEFT (-12046 3225);
DISPLAY 1.170213 (-12046 3225);
PAINT WHITE (-12046 3225);
FORCENOTE
SVID
(-11446 3100) 0;
DISPLAY LEFT (-11446 3100);
DISPLAY 0.808511 (-11446 3100);
PAINT WHITE (-11446 3100);
FORCENOTE
RAIL
(-11996 3100) 0;
DISPLAY LEFT (-11996 3100);
DISPLAY 0.808511 (-11996 3100);
PAINT WHITE (-11996 3100);
FORCENOTE
00H
(-11421 3000) 0;
DISPLAY LEFT (-11421 3000);
DISPLAY 0.638298 (-11421 3000);
PAINT WHITE (-11421 3000);
FORCENOTE
PVCCD_HV_CPU0
(-12121 3000) 0;
DISPLAY LEFT (-12121 3000);
DISPLAY 0.638298 (-12121 3000);
PAINT WHITE (-12121 3000);
FORCENOTE
63H/C6H
(-11096 3000) 0;
DISPLAY LEFT (-11096 3000);
DISPLAY 0.638298 (-11096 3000);
PAINT WHITE (-11096 3000);
FORCENOTE
SVID ADDRESS=00H BUS#1
(-4625 8075) 0;
DISPLAY LEFT (-4625 8075);
DISPLAY 0.936170 (-4625 8075);
PAINT WHITE (-4625 8075);
FORCENOTE
PROTOCOL ID=07H (VR13 5MV VID)
(-4625 8000) 0;
DISPLAY LEFT (-4625 8000);
DISPLAY 0.936170 (-4625 8000);
PAINT WHITE (-4625 8000);
FORCENOTE
PDG REV.1.6 FOR SPR+HBM
(-4625 7925) 0;
DISPLAY LEFT (-4625 7925);
DISPLAY 0.936170 (-4625 7925);
PAINT RED (-4625 7925);
FORCENOTE
OCP=35A
(-4625 8525) 0;
DISPLAY LEFT (-4625 8525);
DISPLAY 0.936170 (-4625 8525);
PAINT WHITE (-4625 8525);
FORCENOTE
VBOOT=1.1V
(-4625 9200) 0;
DISPLAY LEFT (-4625 9200);
DISPLAY 0.936170 (-4625 9200);
PAINT WHITE (-4625 9200);
FORCENOTE
RIPPLE=+/-10MV
(-4625 8975) 0;
DISPLAY LEFT (-4625 8975);
DISPLAY 0.936170 (-4625 8975);
PAINT RED (-4625 8975);
FORCENOTE
DC=+/-0.5% OF VID
(-4625 8900) 0;
DISPLAY LEFT (-4625 8900);
DISPLAY 0.936170 (-4625 8900);
PAINT WHITE (-4625 8900);
FORCENOTE
MAX VR OFFSET=5MV
(-4625 9050) 0;
DISPLAY LEFT (-4625 9050);
DISPLAY 0.936170 (-4625 9050);
PAINT WHITE (-4625 9050);
FORCENOTE
20220808 UPDATE PDG REV 1.6
(-5075 7750) 0;
DISPLAY LEFT (-5075 7750);
DISPLAY 1.595745 (-5075 7750);
QUIT
